FILE_TYPE = MACRO_DRAWING;
SET COLOR_WIRE YELLOW;
SET COLOR_PROP ORANGE;
SET COLOR_DOT WHITE;
SET COLOR_ARC YELLOW;
SET COLOR_BODY GREEN;
SET COLOR_NOTE PURPLE;
SET PROP_DISPLAY VALUE;
SET PAGE_NUMBER P45;
FORCEADD OFFPAGE..1
(-8075 -3175);
FORCEPROP 2 LAST $XR0 125 
J 0
(-8357 -3175);
DISPLAY 0.638298 (-8357 -3175);
PAINT MONO (-8357 -3175);
FORCEPROP 2 LAST CDS_LIB standard
J 0
(-8075 -3175);
PAINT MONO (-8075 -3175);
DISPLAY INVISIBLE (-8075 -3175);
FORCEPROP 1 LAST OFFPAGE TRUE
J 0
(-7750 -3300);
DISPLAY 0.872340 (-7750 -3300);
DISPLAY INVISIBLE (-7750 -3300);
FORCEPROP 1 LAST COMMENT_BODY TRUE
J 0
(-7950 -3275);
DISPLAY 0.872340 (-7950 -3275);
PAINT GREEN (-7950 -3275);
DISPLAY INVISIBLE (-7950 -3275);
FORCEPROP 2 LAST PATH I1
J 0
(-8025 -3100);
DISPLAY 1.021277 (-8025 -3100);
DISPLAY INVISIBLE (-8025 -3100);
FORCEADD OFFPAGE..1
(-8075 -3075);
FORCEPROP 2 LAST $XR0 125 
J 0
(-8357 -3075);
DISPLAY 0.638298 (-8357 -3075);
PAINT MONO (-8357 -3075);
FORCEPROP 2 LAST CDS_LIB standard
J 0
(-8075 -3075);
PAINT MONO (-8075 -3075);
DISPLAY INVISIBLE (-8075 -3075);
FORCEPROP 1 LAST OFFPAGE TRUE
J 0
(-7750 -3200);
DISPLAY 0.872340 (-7750 -3200);
DISPLAY INVISIBLE (-7750 -3200);
FORCEPROP 1 LAST COMMENT_BODY TRUE
J 0
(-7950 -3175);
DISPLAY 0.872340 (-7950 -3175);
PAINT GREEN (-7950 -3175);
DISPLAY INVISIBLE (-7950 -3175);
FORCEPROP 2 LAST PATH I10
J 0
(-8025 -3000);
DISPLAY 1.021277 (-8025 -3000);
DISPLAY INVISIBLE (-8025 -3000);
FORCEADD OFFPAGE..1
(-8075 -2875);
FORCEPROP 2 LAST $XR0 125 
J 0
(-8357 -2875);
DISPLAY 0.638298 (-8357 -2875);
PAINT MONO (-8357 -2875);
FORCEPROP 2 LAST CDS_LIB standard
J 0
(-8075 -2875);
PAINT MONO (-8075 -2875);
DISPLAY INVISIBLE (-8075 -2875);
FORCEPROP 1 LAST OFFPAGE TRUE
J 0
(-7750 -3000);
DISPLAY 0.872340 (-7750 -3000);
DISPLAY INVISIBLE (-7750 -3000);
FORCEPROP 1 LAST COMMENT_BODY TRUE
J 0
(-7950 -2975);
DISPLAY 0.872340 (-7950 -2975);
PAINT GREEN (-7950 -2975);
DISPLAY INVISIBLE (-7950 -2975);
FORCEPROP 2 LAST PATH I11
J 0
(-8025 -2800);
DISPLAY 1.021277 (-8025 -2800);
DISPLAY INVISIBLE (-8025 -2800);
FORCEADD OFFPAGE..1
(-8075 -1975);
FORCEPROP 2 LAST $XR0 14 
J 0
(-8326 -1975);
DISPLAY 0.638298 (-8326 -1975);
PAINT MONO (-8326 -1975);
FORCEPROP 2 LAST CDS_LIB standard
J 0
(-8075 -1975);
PAINT MONO (-8075 -1975);
DISPLAY INVISIBLE (-8075 -1975);
FORCEPROP 1 LAST OFFPAGE TRUE
J 0
(-7750 -2100);
DISPLAY 0.872340 (-7750 -2100);
DISPLAY INVISIBLE (-7750 -2100);
FORCEPROP 1 LAST COMMENT_BODY TRUE
J 0
(-7950 -2075);
DISPLAY 0.872340 (-7950 -2075);
PAINT GREEN (-7950 -2075);
DISPLAY INVISIBLE (-7950 -2075);
FORCEPROP 2 LAST PATH I13
J 0
(-8025 -1900);
DISPLAY 1.021277 (-8025 -1900);
DISPLAY INVISIBLE (-8025 -1900);
FORCEADD OFFPAGE..2
R 2
(-8075 -2025);
FORCEPROP 2 LAST $XR0 14 
J 0
(-8299 -2025);
DISPLAY 0.638298 (-8299 -2025);
PAINT MONO (-8299 -2025);
FORCEPROP 2 LAST CDS_LIB standard
J 0
(-8075 -2025);
PAINT MONO (-8075 -2025);
DISPLAY INVISIBLE (-8075 -2025);
FORCEPROP 1 LAST OFFPAGE TRUE
J 2
(-8400 -2150);
DISPLAY 0.872340 (-8400 -2150);
DISPLAY INVISIBLE (-8400 -2150);
FORCEPROP 1 LAST COMMENT_BODY TRUE
J 2
(-8030 -2120);
DISPLAY 0.872340 (-8030 -2120);
PAINT GREEN (-8030 -2120);
DISPLAY INVISIBLE (-8030 -2120);
FORCEPROP 2 LAST PATH I14
J 0
(-8025 -1950);
DISPLAY 1.021277 (-8025 -1950);
DISPLAY INVISIBLE (-8025 -1950);
FORCEADD OFFPAGE..1
(-8075 -1575);
FORCEPROP 2 LAST $XR0 119 
J 0
(-8357 -1575);
DISPLAY 0.638298 (-8357 -1575);
PAINT MONO (-8357 -1575);
FORCEPROP 2 LAST CDS_LIB standard
J 0
(-8075 -1575);
PAINT MONO (-8075 -1575);
DISPLAY INVISIBLE (-8075 -1575);
FORCEPROP 1 LAST OFFPAGE TRUE
J 0
(-7750 -1700);
DISPLAY 0.872340 (-7750 -1700);
DISPLAY INVISIBLE (-7750 -1700);
FORCEPROP 1 LAST COMMENT_BODY TRUE
J 0
(-7950 -1675);
DISPLAY 0.872340 (-7950 -1675);
PAINT GREEN (-7950 -1675);
DISPLAY INVISIBLE (-7950 -1675);
FORCEPROP 2 LAST PATH I16
J 0
(-8025 -1500);
DISPLAY 1.021277 (-8025 -1500);
DISPLAY INVISIBLE (-8025 -1500);
FORCEADD OFFPAGE..1
(-8075 -1425);
FORCEPROP 2 LAST $XR0 119 
J 0
(-8357 -1425);
DISPLAY 0.638298 (-8357 -1425);
PAINT MONO (-8357 -1425);
FORCEPROP 2 LAST CDS_LIB standard
J 0
(-8075 -1425);
PAINT MONO (-8075 -1425);
DISPLAY INVISIBLE (-8075 -1425);
FORCEPROP 1 LAST OFFPAGE TRUE
J 0
(-7750 -1550);
DISPLAY 0.872340 (-7750 -1550);
DISPLAY INVISIBLE (-7750 -1550);
FORCEPROP 1 LAST COMMENT_BODY TRUE
J 0
(-7950 -1525);
DISPLAY 0.872340 (-7950 -1525);
PAINT GREEN (-7950 -1525);
DISPLAY INVISIBLE (-7950 -1525);
FORCEPROP 2 LAST PATH I17
J 0
(-8025 -1350);
DISPLAY 1.021277 (-8025 -1350);
DISPLAY INVISIBLE (-8025 -1350);
FORCEADD OFFPAGE..2
R 2
(-8075 -1525);
FORCEPROP 2 LAST $XR1 222 
J 0
(-8450 -1525);
DISPLAY 0.638298 (-8450 -1525);
PAINT MONO (-8450 -1525);
FORCEPROP 2 LAST $XR0 133 
J 0
(-8330 -1525);
DISPLAY 0.638298 (-8330 -1525);
PAINT MONO (-8330 -1525);
FORCEPROP 2 LAST CDS_LIB standard
J 0
(-8075 -1525);
PAINT MONO (-8075 -1525);
DISPLAY INVISIBLE (-8075 -1525);
FORCEPROP 1 LAST OFFPAGE TRUE
J 2
(-8400 -1650);
DISPLAY 0.872340 (-8400 -1650);
DISPLAY INVISIBLE (-8400 -1650);
FORCEPROP 1 LAST COMMENT_BODY TRUE
J 2
(-8030 -1620);
DISPLAY 0.872340 (-8030 -1620);
PAINT GREEN (-8030 -1620);
DISPLAY INVISIBLE (-8030 -1620);
FORCEPROP 2 LAST PATH I18
J 0
(-8025 -1450);
DISPLAY 1.021277 (-8025 -1450);
DISPLAY INVISIBLE (-8025 -1450);
FORCEADD OFFPAGE..1
(-8075 -1325);
FORCEPROP 2 LAST $XR0 235 
J 0
(-8357 -1325);
DISPLAY 0.638298 (-8357 -1325);
PAINT MONO (-8357 -1325);
FORCEPROP 2 LAST CDS_LIB standard
J 0
(-8075 -1325);
PAINT MONO (-8075 -1325);
DISPLAY INVISIBLE (-8075 -1325);
FORCEPROP 1 LAST OFFPAGE TRUE
J 0
(-7750 -1450);
DISPLAY 0.872340 (-7750 -1450);
DISPLAY INVISIBLE (-7750 -1450);
FORCEPROP 1 LAST COMMENT_BODY TRUE
J 0
(-7950 -1425);
DISPLAY 0.872340 (-7950 -1425);
PAINT GREEN (-7950 -1425);
DISPLAY INVISIBLE (-7950 -1425);
FORCEPROP 2 LAST PATH I19
J 0
(-8025 -1250);
DISPLAY 1.021277 (-8025 -1250);
DISPLAY INVISIBLE (-8025 -1250);
FORCEADD OFFPAGE..1
(-8075 -1125);
FORCEPROP 2 LAST $XR0 127 
J 0
(-8357 -1125);
DISPLAY 0.638298 (-8357 -1125);
PAINT MONO (-8357 -1125);
FORCEPROP 2 LAST CDS_LIB standard
J 0
(-8075 -1125);
PAINT MONO (-8075 -1125);
DISPLAY INVISIBLE (-8075 -1125);
FORCEPROP 1 LAST OFFPAGE TRUE
J 0
(-7750 -1250);
DISPLAY 0.872340 (-7750 -1250);
DISPLAY INVISIBLE (-7750 -1250);
FORCEPROP 1 LAST COMMENT_BODY TRUE
J 0
(-7950 -1225);
DISPLAY 0.872340 (-7950 -1225);
PAINT GREEN (-7950 -1225);
DISPLAY INVISIBLE (-7950 -1225);
FORCEPROP 2 LAST PATH I20
J 0
(-8025 -1050);
DISPLAY 1.021277 (-8025 -1050);
DISPLAY INVISIBLE (-8025 -1050);
FORCEADD OFFPAGE..3
R 2
(-8075 -1275);
FORCEPROP 2 LAST $XR0 235 
J 0
(-8385 -1275);
DISPLAY 0.638298 (-8385 -1275);
PAINT MONO (-8385 -1275);
FORCEPROP 2 LAST CDS_LIB standard
J 0
(-8075 -1275);
DISPLAY INVISIBLE (-8075 -1275);
FORCEPROP 1 LAST OFFPAGE TRUE
J 2
(-8400 -1400);
DISPLAY 0.872340 (-8400 -1400);
DISPLAY INVISIBLE (-8400 -1400);
FORCEPROP 1 LAST COMMENT_BODY TRUE
J 2
(-8025 -1375);
DISPLAY 0.872340 (-8025 -1375);
PAINT GREEN (-8025 -1375);
DISPLAY INVISIBLE (-8025 -1375);
FORCEPROP 2 LAST PATH I21
J 0
(-8025 -1200);
DISPLAY 1.021277 (-8025 -1200);
DISPLAY INVISIBLE (-8025 -1200);
FORCEADD OFFPAGE..2
R 2
(-8075 -1225);
FORCEPROP 2 LAST $XR0 235 
J 0
(-8330 -1225);
DISPLAY 0.638298 (-8330 -1225);
PAINT MONO (-8330 -1225);
FORCEPROP 2 LAST CDS_LIB standard
J 0
(-8075 -1225);
PAINT MONO (-8075 -1225);
DISPLAY INVISIBLE (-8075 -1225);
FORCEPROP 1 LAST OFFPAGE TRUE
J 2
(-8400 -1350);
DISPLAY 0.872340 (-8400 -1350);
DISPLAY INVISIBLE (-8400 -1350);
FORCEPROP 1 LAST COMMENT_BODY TRUE
J 2
(-8030 -1320);
DISPLAY 0.872340 (-8030 -1320);
PAINT GREEN (-8030 -1320);
DISPLAY INVISIBLE (-8030 -1320);
FORCEPROP 2 LAST PATH I22
J 0
(-8025 -1150);
DISPLAY 1.021277 (-8025 -1150);
DISPLAY INVISIBLE (-8025 -1150);
FORCEADD OFFPAGE..1
(-8075 -1075);
FORCEPROP 2 LAST $XR0 127 
J 0
(-8357 -1075);
DISPLAY 0.638298 (-8357 -1075);
PAINT MONO (-8357 -1075);
FORCEPROP 2 LAST CDS_LIB standard
J 0
(-8075 -1075);
PAINT MONO (-8075 -1075);
DISPLAY INVISIBLE (-8075 -1075);
FORCEPROP 1 LAST OFFPAGE TRUE
J 0
(-7750 -1200);
DISPLAY 0.872340 (-7750 -1200);
DISPLAY INVISIBLE (-7750 -1200);
FORCEPROP 1 LAST COMMENT_BODY TRUE
J 0
(-7950 -1175);
DISPLAY 0.872340 (-7950 -1175);
PAINT GREEN (-7950 -1175);
DISPLAY INVISIBLE (-7950 -1175);
FORCEPROP 2 LAST PATH I23
J 0
(-8025 -1000);
DISPLAY 1.021277 (-8025 -1000);
DISPLAY INVISIBLE (-8025 -1000);
FORCEADD SOCKET4677_AZIF0045P001C01CS..2
(-5750 -1925);
FORCEPROP 1 LAST PART_NUMBER DGA^7000023
J 0
(-6850 -425);
DISPLAY 0.723404 (-6850 -425);
PAINT GREEN (-6850 -425);
DISPLAY INVISIBLE (-6850 -425);
FORCEPROP 2 LAST PART_TYPE SMLF
J 0
(-6850 -250);
DISPLAY 1.021277 (-6850 -250);
FORCEPROP 1 LAST MATERIAL IO
J 0
(-6850 -500);
DISPLAY 0.723404 (-6850 -500);
PAINT GREEN (-6850 -500);
FORCEPROP 2 LAST VALUE SOCKET4677_AZIF0045-P001C01CS
J 0
(-6850 -300);
DISPLAY 1.021277 (-6850 -300);
FORCEPROP 1 LAST $LOCATION U1
J 0
(-6850 -350);
DISPLAY 0.723404 (-6850 -350);
PAINT GREEN (-6850 -350);
FORCEPROP 0 LASTPIN (-4525 -1275) $PN BP24
J 0
(-4515 -1265);
DISPLAY 0.680851 (-4515 -1265);
PAINT MONO (-4515 -1265);
FORCEPROP 0 LASTPIN (-6975 -1325) $PN BV26
J 2
(-6985 -1315);
DISPLAY 0.680851 (-6985 -1315);
PAINT MONO (-6985 -1315);
FORCEPROP 0 LASTPIN (-6975 -1225) $PN CA25
J 2
(-6985 -1215);
DISPLAY 0.680851 (-6985 -1215);
PAINT MONO (-6985 -1215);
FORCEPROP 0 LASTPIN (-6975 -1275) $PN BY26
J 2
(-6985 -1265);
DISPLAY 0.680851 (-6985 -1265);
PAINT MONO (-6985 -1265);
FORCEPROP 0 LASTPIN (-6975 -2875) $PN A43
J 2
(-6985 -2865);
DISPLAY 0.680851 (-6985 -2865);
PAINT MONO (-6985 -2865);
FORCEPROP 0 LASTPIN (-6975 -2925) $PN F47
J 2
(-6985 -2915);
DISPLAY 0.680851 (-6985 -2915);
PAINT MONO (-6985 -2915);
FORCEPROP 0 LASTPIN (-6975 -2975) $PN CY44
J 2
(-6985 -2965);
DISPLAY 0.680851 (-6985 -2965);
PAINT MONO (-6985 -2965);
FORCEPROP 0 LASTPIN (-6975 -3025) $PN CW45
J 2
(-6985 -3015);
DISPLAY 0.680851 (-6985 -3015);
PAINT MONO (-6985 -3015);
FORCEPROP 0 LASTPIN (-4525 -1725) $PN AV57
J 0
(-4515 -1715);
DISPLAY 0.680851 (-4515 -1715);
PAINT MONO (-4515 -1715);
FORCEPROP 0 LASTPIN (-4525 -1375) $PN AU21
J 0
(-4515 -1365);
DISPLAY 0.680851 (-4515 -1365);
PAINT MONO (-4515 -1365);
FORCEPROP 0 LASTPIN (-4525 -1425) $PN CF26
J 0
(-4515 -1415);
DISPLAY 0.680851 (-4515 -1415);
PAINT MONO (-4515 -1415);
FORCEPROP 0 LASTPIN (-4525 -1475) $PN AV24
J 0
(-4515 -1465);
DISPLAY 0.680851 (-4515 -1465);
PAINT MONO (-4515 -1465);
FORCEPROP 0 LASTPIN (-4525 -1575) $PN AV18
J 0
(-4515 -1565);
DISPLAY 0.680851 (-4515 -1565);
PAINT MONO (-4515 -1565);
FORCEPROP 0 LASTPIN (-6975 -2025) $PN CW39
J 2
(-6985 -2015);
DISPLAY 0.680851 (-6985 -2015);
PAINT MONO (-6985 -2015);
FORCEPROP 0 LASTPIN (-6975 -2125) $PN CP26
J 2
(-6985 -2115);
DISPLAY 0.680851 (-6985 -2115);
PAINT MONO (-6985 -2115);
FORCEPROP 0 LASTPIN (-6975 -2225) $PN CM26
J 2
(-6985 -2215);
DISPLAY 0.680851 (-6985 -2215);
PAINT MONO (-6985 -2215);
FORCEPROP 0 LASTPIN (-6975 -2325) $PN CD24
J 2
(-6985 -2315);
DISPLAY 0.680851 (-6985 -2315);
PAINT MONO (-6985 -2315);
FORCEPROP 0 LASTPIN (-6975 -2425) $PN CV18
J 2
(-6985 -2415);
DISPLAY 0.680851 (-6985 -2415);
PAINT MONO (-6985 -2415);
FORCEPROP 0 LASTPIN (-6975 -2525) $PN CE23
J 2
(-6985 -2515);
DISPLAY 0.680851 (-6985 -2515);
PAINT MONO (-6985 -2515);
FORCEPROP 0 LASTPIN (-6975 -2625) $PN CC25
J 2
(-6985 -2615);
DISPLAY 0.680851 (-6985 -2615);
PAINT MONO (-6985 -2615);
FORCEPROP 0 LASTPIN (-6975 -1925) $PN CY40
J 2
(-6985 -1915);
DISPLAY 0.680851 (-6985 -1915);
PAINT MONO (-6985 -1915);
FORCEPROP 0 LASTPIN (-4525 -1825) $PN CP20
J 0
(-4515 -1815);
DISPLAY 0.680851 (-4515 -1815);
PAINT MONO (-4515 -1815);
FORCEPROP 0 LASTPIN (-6975 -1975) $PN CN25
J 2
(-6985 -1965);
DISPLAY 0.680851 (-6985 -1965);
PAINT MONO (-6985 -1965);
FORCEPROP 0 LASTPIN (-6975 -2075) $PN CL25
J 2
(-6985 -2065);
DISPLAY 0.680851 (-6985 -2065);
PAINT MONO (-6985 -2065);
FORCEPROP 0 LASTPIN (-6975 -2175) $PN CH26
J 2
(-6985 -2165);
DISPLAY 0.680851 (-6985 -2165);
PAINT MONO (-6985 -2165);
FORCEPROP 0 LASTPIN (-6975 -2275) $PN CE25
J 2
(-6985 -2265);
DISPLAY 0.680851 (-6985 -2265);
PAINT MONO (-6985 -2265);
FORCEPROP 0 LASTPIN (-6975 -2375) $PN CR19
J 2
(-6985 -2365);
DISPLAY 0.680851 (-6985 -2365);
PAINT MONO (-6985 -2365);
FORCEPROP 0 LASTPIN (-6975 -2475) $PN CH24
J 2
(-6985 -2465);
DISPLAY 0.680851 (-6985 -2465);
PAINT MONO (-6985 -2465);
FORCEPROP 0 LASTPIN (-6975 -2575) $PN CF24
J 2
(-6985 -2565);
DISPLAY 0.680851 (-6985 -2565);
PAINT MONO (-6985 -2565);
FORCEPROP 0 LASTPIN (-6975 -1875) $PN DA39
J 2
(-6985 -1865);
DISPLAY 0.680851 (-6985 -1865);
PAINT MONO (-6985 -1865);
FORCEPROP 0 LASTPIN (-4525 -1325) $PN AU19
J 0
(-4515 -1315);
DISPLAY 0.680851 (-4515 -1315);
PAINT MONO (-4515 -1315);
FORCEPROP 0 LASTPIN (-6975 -3175) $PN BH61
J 2
(-6985 -3165);
DISPLAY 0.680851 (-6985 -3165);
PAINT MONO (-6985 -3165);
FORCEPROP 0 LASTPIN (-6975 -1525) $PN CG66
J 2
(-6985 -1515);
DISPLAY 0.680851 (-6985 -1515);
PAINT MONO (-6985 -1515);
FORCEPROP 0 LASTPIN (-4525 -775) $PN BK26
J 0
(-4515 -765);
DISPLAY 0.680851 (-4515 -765);
PAINT MONO (-4515 -765);
FORCEPROP 0 LASTPIN (-4525 -975) $PN BJ25
J 0
(-4515 -965);
DISPLAY 0.680851 (-4515 -965);
PAINT MONO (-4515 -965);
FORCEPROP 0 LASTPIN (-4525 -725) $PN BH26
J 0
(-4515 -715);
DISPLAY 0.680851 (-4515 -715);
PAINT MONO (-4515 -715);
FORCEPROP 0 LASTPIN (-4525 -925) $PN BF26
J 0
(-4515 -915);
DISPLAY 0.680851 (-4515 -915);
PAINT MONO (-4515 -915);
FORCEPROP 0 LASTPIN (-4525 -675) $PN BD26
J 0
(-4515 -665);
DISPLAY 0.680851 (-4515 -665);
PAINT MONO (-4515 -665);
FORCEPROP 0 LASTPIN (-4525 -875) $PN BL25
J 0
(-4515 -865);
DISPLAY 0.680851 (-4515 -865);
PAINT MONO (-4515 -865);
FORCEPROP 0 LASTPIN (-6975 -1575) $PN AY20
J 2
(-6985 -1565);
DISPLAY 0.680851 (-6985 -1565);
PAINT MONO (-6985 -1565);
FORCEPROP 0 LASTPIN (-4525 -1525) $PN BL62
J 0
(-4515 -1515);
DISPLAY 0.680851 (-4515 -1515);
PAINT MONO (-4515 -1515);
FORCEPROP 0 LASTPIN (-4525 -1075) $PN BF22
J 0
(-4515 -1065);
DISPLAY 0.680851 (-4515 -1065);
PAINT MONO (-4515 -1065);
FORCEPROP 0 LASTPIN (-4525 -1125) $PN AY22
J 0
(-4515 -1115);
DISPLAY 0.680851 (-4515 -1115);
PAINT MONO (-4515 -1115);
FORCEPROP 0 LASTPIN (-4525 -1175) $PN BD22
J 0
(-4515 -1165);
DISPLAY 0.680851 (-4515 -1165);
PAINT MONO (-4515 -1165);
FORCEPROP 0 LASTPIN (-6975 -1025) $PN CR70
J 2
(-6985 -1015);
DISPLAY 0.680851 (-6985 -1015);
PAINT MONO (-6985 -1015);
FORCEPROP 0 LASTPIN (-6975 -1075) $PN CT71
J 2
(-6985 -1065);
DISPLAY 0.680851 (-6985 -1065);
PAINT MONO (-6985 -1065);
FORCEPROP 0 LASTPIN (-6975 -1125) $PN CP71
J 2
(-6985 -1115);
DISPLAY 0.680851 (-6985 -1115);
PAINT MONO (-6985 -1115);
FORCEPROP 0 LASTPIN (-6975 -875) $PN CU70
J 2
(-6985 -865);
DISPLAY 0.680851 (-6985 -865);
PAINT MONO (-6985 -865);
FORCEPROP 0 LASTPIN (-6975 -925) $PN CM71
J 2
(-6985 -915);
DISPLAY 0.680851 (-6985 -915);
PAINT MONO (-6985 -915);
FORCEPROP 0 LASTPIN (-6975 -975) $PN CR72
J 2
(-6985 -965);
DISPLAY 0.680851 (-6985 -965);
PAINT MONO (-6985 -965);
FORCEPROP 0 LASTPIN (-6975 -3075) $PN AV20
J 2
(-6985 -3065);
DISPLAY 0.680851 (-6985 -3065);
PAINT MONO (-6985 -3065);
FORCEPROP 0 LASTPIN (-4525 -2175) $PN AT24
J 0
(-4515 -2165);
DISPLAY 0.680851 (-4515 -2165);
PAINT MONO (-4515 -2165);
FORCEPROP 0 LASTPIN (-4525 -2225) $PN AU25
J 0
(-4515 -2215);
DISPLAY 0.680851 (-4515 -2215);
PAINT MONO (-4515 -2215);
FORCEPROP 0 LASTPIN (-4525 -2275) $PN AV26
J 0
(-4515 -2265);
DISPLAY 0.680851 (-4515 -2265);
PAINT MONO (-4515 -2265);
FORCEPROP 0 LASTPIN (-4525 -1775) $PN AV59
J 0
(-4515 -1765);
DISPLAY 0.680851 (-4515 -1765);
PAINT MONO (-4515 -1765);
FORCEPROP 0 LASTPIN (-4525 -2125) $PN AY26
J 0
(-4515 -2115);
DISPLAY 0.680851 (-4515 -2115);
PAINT MONO (-4515 -2115);
FORCEPROP 0 LASTPIN (-4525 -2475) $PN AY65
J 0
(-4515 -2465);
DISPLAY 0.680851 (-4515 -2465);
PAINT MONO (-4515 -2465);
FORCEPROP 0 LASTPIN (-4525 -2525) $PN BJ70
J 0
(-4515 -2515);
DISPLAY 0.680851 (-4515 -2515);
PAINT MONO (-4515 -2515);
FORCEPROP 0 LASTPIN (-4525 -2425) $PN BP67
J 0
(-4515 -2415);
DISPLAY 0.680851 (-4515 -2415);
PAINT MONO (-4515 -2415);
FORCEPROP 0 LASTPIN (-4525 -2375) $PN BP69
J 0
(-4515 -2365);
DISPLAY 0.680851 (-4515 -2365);
PAINT MONO (-4515 -2365);
FORCEPROP 0 LASTPIN (-6975 -1425) $PN CH22
J 2
(-6985 -1415);
DISPLAY 0.680851 (-6985 -1415);
PAINT MONO (-6985 -1415);
FORCEPROP 0 LASTPIN (-4525 -2875) $PN CJ62
J 0
(-4515 -2865);
DISPLAY 0.680851 (-4515 -2865);
PAINT MONO (-4515 -2865);
FORCEPROP 0 LASTPIN (-6975 -1825) $PN CL21
J 2
(-6985 -1815);
DISPLAY 0.680851 (-6985 -1815);
PAINT MONO (-6985 -1815);
FORCEPROP 0 LASTPIN (-4525 -3025) $PN CL64
J 0
(-4515 -3015);
DISPLAY 0.680851 (-4515 -3015);
PAINT MONO (-4515 -3015);
FORCEPROP 0 LASTPIN (-4525 -2975) $PN CM63
J 0
(-4515 -2965);
DISPLAY 0.680851 (-4515 -2965);
PAINT MONO (-4515 -2965);
FORCEPROP 0 LASTPIN (-4525 -2925) $PN CN62
J 0
(-4515 -2915);
DISPLAY 0.680851 (-4515 -2915);
PAINT MONO (-4515 -2915);
FORCEPROP 0 LASTPIN (-4525 -2625) $PN CR23
J 0
(-4515 -2615);
DISPLAY 0.680851 (-4515 -2615);
PAINT MONO (-4515 -2615);
FORCEPROP 0 LASTPIN (-4525 -2725) $PN CV24
J 0
(-4515 -2715);
DISPLAY 0.680851 (-4515 -2715);
PAINT MONO (-4515 -2715);
FORCEPROP 0 LASTPIN (-4525 -2775) $PN CW23
J 0
(-4515 -2765);
DISPLAY 0.680851 (-4515 -2765);
PAINT MONO (-4515 -2765);
FORCEPROP 0 LASTPIN (-4525 -2675) $PN CW25
J 0
(-4515 -2665);
DISPLAY 0.680851 (-4515 -2665);
PAINT MONO (-4515 -2665);
FORCEPROP 0 LASTPIN (-4525 -1975) $PN CW68
J 0
(-4515 -1965);
DISPLAY 0.680851 (-4515 -1965);
PAINT MONO (-4515 -1965);
FORCEPROP 2 LAST CDS_LIB pure_quanta
J 0
(-5750 -1925);
DISPLAY INVISIBLE (-5750 -1925);
FORCEPROP 1 LAST NEEDS_NO_SIZE TRUE
J 0
(-5750 -1925);
DISPLAY 0.723404 (-5750 -1925);
PAINT GREEN (-5750 -1925);
DISPLAY INVISIBLE (-5750 -1925);
FORCEPROP 1 LAST CDS_LMAN_SYM_OUTLINE -1100,1400,1050,-1400
J 0
(-5750 -1925);
DISPLAY 0.468085 (-5750 -1925);
PAINT GREEN (-5750 -1925);
DISPLAY INVISIBLE (-5750 -1925);
FORCEPROP 2 LAST CDS_LOCATION U1
J 0
(-6850 -200);
DISPLAY 1.021277 (-6850 -200);
DISPLAY INVISIBLE (-6850 -200);
FORCEPROP 0 LAST $SEC 2
J 0
(-6850 -200);
DISPLAY 0.680851 (-6850 -200);
PAINT MONO (-6850 -200);
DISPLAY INVISIBLE (-6850 -200);
FORCEPROP 2 LAST CDS_SEC 2
J 0
(-6850 -200);
DISPLAY 1.021277 (-6850 -200);
DISPLAY INVISIBLE (-6850 -200);
FORCEPROP 1 LAST PATH I29
J 0
(-5750 -1925);
DISPLAY 0.723404 (-5750 -1925);
PAINT GREEN (-5750 -1925);
DISPLAY INVISIBLE (-5750 -1925);
FORCEADD OFFPAGE..1
(-8075 -975);
FORCEPROP 2 LAST $XR0 127 
J 0
(-8357 -975);
DISPLAY 0.638298 (-8357 -975);
PAINT MONO (-8357 -975);
FORCEPROP 2 LAST CDS_LIB standard
J 0
(-8075 -975);
PAINT MONO (-8075 -975);
DISPLAY INVISIBLE (-8075 -975);
FORCEPROP 1 LAST OFFPAGE TRUE
J 0
(-7750 -1100);
DISPLAY 0.872340 (-7750 -1100);
DISPLAY INVISIBLE (-7750 -1100);
FORCEPROP 1 LAST COMMENT_BODY TRUE
J 0
(-7950 -1075);
DISPLAY 0.872340 (-7950 -1075);
PAINT GREEN (-7950 -1075);
DISPLAY INVISIBLE (-7950 -1075);
FORCEPROP 2 LAST PATH I32
J 0
(-8025 -900);
DISPLAY 1.021277 (-8025 -900);
DISPLAY INVISIBLE (-8025 -900);
FORCEADD OFFPAGE..1
(-8075 -1025);
FORCEPROP 2 LAST $XR0 127 
J 0
(-8357 -1025);
DISPLAY 0.638298 (-8357 -1025);
PAINT MONO (-8357 -1025);
FORCEPROP 2 LAST CDS_LIB standard
J 0
(-8075 -1025);
PAINT MONO (-8075 -1025);
DISPLAY INVISIBLE (-8075 -1025);
FORCEPROP 1 LAST OFFPAGE TRUE
J 0
(-7750 -1150);
DISPLAY 0.872340 (-7750 -1150);
DISPLAY INVISIBLE (-7750 -1150);
FORCEPROP 1 LAST COMMENT_BODY TRUE
J 0
(-7950 -1125);
DISPLAY 0.872340 (-7950 -1125);
PAINT GREEN (-7950 -1125);
DISPLAY INVISIBLE (-7950 -1125);
FORCEPROP 2 LAST PATH I33
J 0
(-8025 -950);
DISPLAY 1.021277 (-8025 -950);
DISPLAY INVISIBLE (-8025 -950);
FORCEADD OFFPAGE..3
(-2800 -1825);
FORCEPROP 2 LAST $XR0 117 
J 0
(-2586 -1825);
DISPLAY 0.638298 (-2586 -1825);
PAINT MONO (-2586 -1825);
FORCEPROP 2 LAST CDS_LIB standard
J 0
(-2800 -1825);
PAINT MONO (-2800 -1825);
DISPLAY INVISIBLE (-2800 -1825);
FORCEPROP 1 LAST OFFPAGE TRUE
J 0
(-2475 -1950);
DISPLAY 1.170213 (-2475 -1950);
PAINT GREEN (-2475 -1950);
DISPLAY INVISIBLE (-2475 -1950);
FORCEPROP 1 LAST COMMENT_BODY TRUE
J 0
(-2850 -1925);
DISPLAY 1.170213 (-2850 -1925);
PAINT GREEN (-2850 -1925);
DISPLAY INVISIBLE (-2850 -1925);
FORCEPROP 2 LAST PATH I38
J 0
(-2600 -1750);
DISPLAY 1.021277 (-2600 -1750);
DISPLAY INVISIBLE (-2600 -1750);
FORCEADD OFFPAGE..4
(-2800 -1725);
FORCEPROP 2 LAST $XR1 14 
J 0
(-2494 -1725);
DISPLAY 0.638298 (-2494 -1725);
PAINT MONO (-2494 -1725);
FORCEPROP 2 LAST $XR0 131 
J 0
(-2614 -1725);
DISPLAY 0.638298 (-2614 -1725);
PAINT MONO (-2614 -1725);
FORCEPROP 2 LAST CDS_LIB standard
J 0
(-2800 -1725);
PAINT MONO (-2800 -1725);
DISPLAY INVISIBLE (-2800 -1725);
FORCEPROP 1 LAST OFFPAGE TRUE
J 0
(-2475 -1850);
DISPLAY 1.170213 (-2475 -1850);
PAINT GREEN (-2475 -1850);
DISPLAY INVISIBLE (-2475 -1850);
FORCEPROP 1 LAST COMMENT_BODY TRUE
J 0
(-2825 -1825);
DISPLAY 1.170213 (-2825 -1825);
PAINT GREEN (-2825 -1825);
DISPLAY INVISIBLE (-2825 -1825);
FORCEPROP 2 LAST PATH I39
J 0
(-2625 -1650);
DISPLAY 1.021277 (-2625 -1650);
DISPLAY INVISIBLE (-2625 -1650);
FORCEADD OFFPAGE..4
(-2800 -1575);
FORCEPROP 2 LAST $XR0 123 
J 0
(-2614 -1575);
DISPLAY 0.638298 (-2614 -1575);
PAINT MONO (-2614 -1575);
FORCEPROP 2 LAST CDS_LIB standard
J 0
(-2800 -1575);
PAINT MONO (-2800 -1575);
DISPLAY INVISIBLE (-2800 -1575);
FORCEPROP 1 LAST OFFPAGE TRUE
J 0
(-2475 -1700);
DISPLAY 1.170213 (-2475 -1700);
PAINT GREEN (-2475 -1700);
DISPLAY INVISIBLE (-2475 -1700);
FORCEPROP 1 LAST COMMENT_BODY TRUE
J 0
(-2825 -1675);
DISPLAY 1.170213 (-2825 -1675);
PAINT GREEN (-2825 -1675);
DISPLAY INVISIBLE (-2825 -1675);
FORCEPROP 2 LAST PATH I41
J 0
(-2625 -1500);
DISPLAY 1.021277 (-2625 -1500);
DISPLAY INVISIBLE (-2625 -1500);
FORCEADD OFFPAGE..2
(-2800 -1525);
FORCEPROP 2 LAST $XR0 121 
J 0
(-2611 -1525);
DISPLAY 0.638298 (-2611 -1525);
PAINT MONO (-2611 -1525);
FORCEPROP 2 LAST CDS_LIB standard
J 0
(-2800 -1525);
PAINT MONO (-2800 -1525);
DISPLAY INVISIBLE (-2800 -1525);
FORCEPROP 1 LAST OFFPAGE TRUE
J 0
(-2475 -1650);
DISPLAY 1.170213 (-2475 -1650);
PAINT GREEN (-2475 -1650);
DISPLAY INVISIBLE (-2475 -1650);
FORCEPROP 1 LAST COMMENT_BODY TRUE
J 0
(-2845 -1620);
DISPLAY 1.170213 (-2845 -1620);
PAINT GREEN (-2845 -1620);
DISPLAY INVISIBLE (-2845 -1620);
FORCEPROP 2 LAST PATH I42
J 0
(-2625 -1450);
DISPLAY 1.021277 (-2625 -1450);
DISPLAY INVISIBLE (-2625 -1450);
FORCEADD OFFPAGE..2
(-2800 -1475);
FORCEPROP 2 LAST $XR0 123 
J 0
(-2611 -1475);
DISPLAY 0.638298 (-2611 -1475);
PAINT MONO (-2611 -1475);
FORCEPROP 2 LAST CDS_LIB standard
J 0
(-2800 -1475);
PAINT MONO (-2800 -1475);
DISPLAY INVISIBLE (-2800 -1475);
FORCEPROP 1 LAST OFFPAGE TRUE
J 0
(-2475 -1600);
DISPLAY 1.170213 (-2475 -1600);
PAINT GREEN (-2475 -1600);
DISPLAY INVISIBLE (-2475 -1600);
FORCEPROP 1 LAST COMMENT_BODY TRUE
J 0
(-2845 -1570);
DISPLAY 1.170213 (-2845 -1570);
PAINT GREEN (-2845 -1570);
DISPLAY INVISIBLE (-2845 -1570);
FORCEPROP 2 LAST PATH I43
J 0
(-2625 -1400);
DISPLAY 1.021277 (-2625 -1400);
DISPLAY INVISIBLE (-2625 -1400);
FORCEADD OFFPAGE..2
(-2800 -1425);
FORCEPROP 2 LAST $XR0 122 
J 0
(-2611 -1425);
DISPLAY 0.638298 (-2611 -1425);
PAINT MONO (-2611 -1425);
FORCEPROP 2 LAST CDS_LIB standard
J 0
(-2800 -1425);
PAINT MONO (-2800 -1425);
DISPLAY INVISIBLE (-2800 -1425);
FORCEPROP 1 LAST OFFPAGE TRUE
J 0
(-2475 -1550);
DISPLAY 1.170213 (-2475 -1550);
PAINT GREEN (-2475 -1550);
DISPLAY INVISIBLE (-2475 -1550);
FORCEPROP 1 LAST COMMENT_BODY TRUE
J 0
(-2845 -1520);
DISPLAY 1.170213 (-2845 -1520);
PAINT GREEN (-2845 -1520);
DISPLAY INVISIBLE (-2845 -1520);
FORCEPROP 2 LAST PATH I44
J 0
(-2625 -1350);
DISPLAY 1.021277 (-2625 -1350);
DISPLAY INVISIBLE (-2625 -1350);
FORCEADD OFFPAGE..4
(-2800 -1375);
FORCEPROP 2 LAST $XR0 122 
J 0
(-2614 -1375);
DISPLAY 0.638298 (-2614 -1375);
PAINT MONO (-2614 -1375);
FORCEPROP 2 LAST CDS_LIB standard
J 0
(-2800 -1375);
PAINT MONO (-2800 -1375);
DISPLAY INVISIBLE (-2800 -1375);
FORCEPROP 1 LAST OFFPAGE TRUE
J 0
(-2475 -1500);
DISPLAY 1.170213 (-2475 -1500);
PAINT GREEN (-2475 -1500);
DISPLAY INVISIBLE (-2475 -1500);
FORCEPROP 1 LAST COMMENT_BODY TRUE
J 0
(-2825 -1475);
DISPLAY 1.170213 (-2825 -1475);
PAINT GREEN (-2825 -1475);
DISPLAY INVISIBLE (-2825 -1475);
FORCEPROP 2 LAST PATH I45
J 0
(-2625 -1300);
DISPLAY 1.021277 (-2625 -1300);
DISPLAY INVISIBLE (-2625 -1300);
FORCEADD OFFPAGE..4
(-2800 -1325);
FORCEPROP 2 LAST $XR0 121 
J 0
(-2584 -1325);
DISPLAY 0.638298 (-2584 -1325);
PAINT MONO (-2584 -1325);
FORCEPROP 2 LAST CDS_LIB standard
J 0
(-2800 -1325);
PAINT MONO (-2800 -1325);
DISPLAY INVISIBLE (-2800 -1325);
FORCEPROP 1 LAST OFFPAGE TRUE
J 0
(-2475 -1450);
DISPLAY 1.170213 (-2475 -1450);
PAINT GREEN (-2475 -1450);
DISPLAY INVISIBLE (-2475 -1450);
FORCEPROP 1 LAST COMMENT_BODY TRUE
J 0
(-2825 -1425);
DISPLAY 1.170213 (-2825 -1425);
PAINT GREEN (-2825 -1425);
DISPLAY INVISIBLE (-2825 -1425);
FORCEPROP 2 LAST PATH I46
J 0
(-2625 -1250);
DISPLAY 1.021277 (-2625 -1250);
DISPLAY INVISIBLE (-2625 -1250);
FORCEADD OFFPAGE..3
(-2800 -1275);
FORCEPROP 2 LAST $XR0 118 
J 0
(-2586 -1275);
DISPLAY 0.638298 (-2586 -1275);
PAINT MONO (-2586 -1275);
FORCEPROP 2 LAST CDS_LIB standard
J 0
(-2800 -1275);
PAINT MONO (-2800 -1275);
DISPLAY INVISIBLE (-2800 -1275);
FORCEPROP 1 LAST OFFPAGE TRUE
J 0
(-2475 -1400);
DISPLAY 1.170213 (-2475 -1400);
PAINT GREEN (-2475 -1400);
DISPLAY INVISIBLE (-2475 -1400);
FORCEPROP 1 LAST COMMENT_BODY TRUE
J 0
(-2850 -1375);
DISPLAY 1.170213 (-2850 -1375);
PAINT GREEN (-2850 -1375);
DISPLAY INVISIBLE (-2850 -1375);
FORCEPROP 2 LAST PATH I47
J 0
(-2600 -1200);
DISPLAY 1.021277 (-2600 -1200);
DISPLAY INVISIBLE (-2600 -1200);
FORCEADD OFFPAGE..2
(-2800 -1175);
FORCEPROP 2 LAST $XR0 225 
J 0
(-2611 -1175);
DISPLAY 0.638298 (-2611 -1175);
PAINT MONO (-2611 -1175);
FORCEPROP 2 LAST CDS_LIB standard
J 0
(-2800 -1175);
PAINT MONO (-2800 -1175);
DISPLAY INVISIBLE (-2800 -1175);
FORCEPROP 1 LAST OFFPAGE TRUE
J 0
(-2475 -1300);
DISPLAY 1.170213 (-2475 -1300);
PAINT GREEN (-2475 -1300);
DISPLAY INVISIBLE (-2475 -1300);
FORCEPROP 1 LAST COMMENT_BODY TRUE
J 0
(-2845 -1270);
DISPLAY 1.170213 (-2845 -1270);
PAINT GREEN (-2845 -1270);
DISPLAY INVISIBLE (-2845 -1270);
FORCEPROP 2 LAST PATH I48
J 0
(-2625 -1100);
DISPLAY 1.021277 (-2625 -1100);
DISPLAY INVISIBLE (-2625 -1100);
FORCEADD OFFPAGE..2
(-2800 -1125);
FORCEPROP 2 LAST $XR0 225 
J 0
(-2611 -1125);
DISPLAY 0.638298 (-2611 -1125);
PAINT MONO (-2611 -1125);
FORCEPROP 2 LAST CDS_LIB standard
J 0
(-2800 -1125);
PAINT MONO (-2800 -1125);
DISPLAY INVISIBLE (-2800 -1125);
FORCEPROP 1 LAST OFFPAGE TRUE
J 0
(-2475 -1250);
DISPLAY 1.170213 (-2475 -1250);
PAINT GREEN (-2475 -1250);
DISPLAY INVISIBLE (-2475 -1250);
FORCEPROP 1 LAST COMMENT_BODY TRUE
J 0
(-2845 -1220);
DISPLAY 1.170213 (-2845 -1220);
PAINT GREEN (-2845 -1220);
DISPLAY INVISIBLE (-2845 -1220);
FORCEPROP 2 LAST PATH I49
J 0
(-2625 -1050);
DISPLAY 1.021277 (-2625 -1050);
DISPLAY INVISIBLE (-2625 -1050);
FORCEADD OFFPAGE..2
(-2800 -1075);
FORCEPROP 2 LAST $XR0 225 
J 0
(-2611 -1075);
DISPLAY 0.638298 (-2611 -1075);
PAINT MONO (-2611 -1075);
FORCEPROP 2 LAST CDS_LIB standard
J 0
(-2800 -1075);
PAINT MONO (-2800 -1075);
DISPLAY INVISIBLE (-2800 -1075);
FORCEPROP 1 LAST OFFPAGE TRUE
J 0
(-2475 -1200);
DISPLAY 1.170213 (-2475 -1200);
PAINT GREEN (-2475 -1200);
DISPLAY INVISIBLE (-2475 -1200);
FORCEPROP 1 LAST COMMENT_BODY TRUE
J 0
(-2845 -1170);
DISPLAY 1.170213 (-2845 -1170);
PAINT GREEN (-2845 -1170);
DISPLAY INVISIBLE (-2845 -1170);
FORCEPROP 2 LAST PATH I50
J 0
(-2625 -1000);
DISPLAY 1.021277 (-2625 -1000);
DISPLAY INVISIBLE (-2625 -1000);
FORCEADD Q_RES..1
(-3400 -875);
FORCEPROP 1 LAST PART_NUMBER CS00002JB13
J 0
(-3275 -900);
DISPLAY 0.404255 (-3275 -900);
DISPLAY INVISIBLE (-3275 -900);
FORCEPROP 1 LAST VALUE 0
J 2
(-3250 -875);
DISPLAY 0.510638 (-3250 -875);
FORCEPROP 1 LAST PACK_TYPE 0402LF
J 0
(-3100 -875);
DISPLAY 0.510638 (-3100 -875);
FORCEPROP 1 LAST TOLERANCE 5%
J 0
(-3175 -875);
DISPLAY 0.510638 (-3175 -875);
FORCEPROP 1 LAST $LOCATION R58
J 0
(-3575 -875);
DISPLAY 0.638298 (-3575 -875);
FORCEPROP 1 LASTPIN (-3500 -875) $PN 1
J 0
(-3488 -863);
DISPLAY 0.787234 (-3488 -863);
FORCEPROP 1 LASTPIN (-3300 -875) $PN 2
J 0
(-3338 -863);
DISPLAY 0.787234 (-3338 -863);
FORCEPROP 2 LAST CDS_LIB pure_quanta
J 0
(-3400 -875);
PAINT MONO (-3400 -875);
DISPLAY INVISIBLE (-3400 -875);
FORCEPROP 1 LAST MATERIAL CHIP
J 0
(-2925 -900);
DISPLAY 0.404255 (-2925 -900);
DISPLAY INVISIBLE (-2925 -900);
FORCEPROP 1 LAST WATTAGE 1/16W
J 2
(-2950 -900);
DISPLAY 0.404255 (-2950 -900);
DISPLAY INVISIBLE (-2950 -900);
FORCEPROP 1 LAST $LOCATION R58
J 0
(-3450 -675);
DISPLAY 1.021277 (-3450 -675);
DISPLAY INVISIBLE (-3450 -675);
FORCEPROP 2 LAST CDS_LOCATION R58
J 0
(-3450 -675);
DISPLAY 1.021277 (-3450 -675);
DISPLAY INVISIBLE (-3450 -675);
FORCEPROP 2 LAST $SEC 1
J 0
(-3450 -675);
DISPLAY 0.680851 (-3450 -675);
PAINT MONO (-3450 -675);
DISPLAY INVISIBLE (-3450 -675);
FORCEPROP 2 LAST CDS_SEC 1
J 0
(-3450 -675);
DISPLAY 1.021277 (-3450 -675);
DISPLAY INVISIBLE (-3450 -675);
FORCEPROP 1 LAST PATH I51
J 0
(-3450 -725);
DISPLAY 0.978723 (-3450 -725);
PAINT WHITE (-3450 -725);
DISPLAY INVISIBLE (-3450 -725);
FORCEADD Q_RES..1
(-3400 -925);
FORCEPROP 1 LAST PART_NUMBER CS00002JB13
J 0
(-3275 -950);
DISPLAY 0.404255 (-3275 -950);
DISPLAY INVISIBLE (-3275 -950);
FORCEPROP 1 LAST VALUE 0
J 2
(-3250 -925);
DISPLAY 0.510638 (-3250 -925);
FORCEPROP 1 LAST TOLERANCE 5%
J 0
(-3175 -925);
DISPLAY 0.510638 (-3175 -925);
FORCEPROP 1 LAST PACK_TYPE 0402LF
J 0
(-3100 -925);
DISPLAY 0.510638 (-3100 -925);
FORCEPROP 1 LAST $LOCATION R59
J 0
(-3575 -925);
DISPLAY 0.638298 (-3575 -925);
FORCEPROP 1 LASTPIN (-3500 -925) $PN 1
J 0
(-3488 -913);
DISPLAY 0.787234 (-3488 -913);
FORCEPROP 1 LASTPIN (-3300 -925) $PN 2
J 0
(-3338 -913);
DISPLAY 0.787234 (-3338 -913);
FORCEPROP 2 LAST CDS_LIB pure_quanta
J 0
(-3400 -925);
PAINT MONO (-3400 -925);
DISPLAY INVISIBLE (-3400 -925);
FORCEPROP 1 LAST WATTAGE 1/16W
J 2
(-2950 -950);
DISPLAY 0.404255 (-2950 -950);
DISPLAY INVISIBLE (-2950 -950);
FORCEPROP 1 LAST MATERIAL CHIP
J 0
(-2925 -950);
DISPLAY 0.404255 (-2925 -950);
DISPLAY INVISIBLE (-2925 -950);
FORCEPROP 1 LAST $LOCATION R59
J 0
(-3450 -725);
DISPLAY 1.021277 (-3450 -725);
DISPLAY INVISIBLE (-3450 -725);
FORCEPROP 2 LAST CDS_LOCATION R59
J 0
(-3450 -725);
DISPLAY 1.021277 (-3450 -725);
DISPLAY INVISIBLE (-3450 -725);
FORCEPROP 2 LAST $SEC 1
J 0
(-3450 -725);
DISPLAY 0.680851 (-3450 -725);
PAINT MONO (-3450 -725);
DISPLAY INVISIBLE (-3450 -725);
FORCEPROP 2 LAST CDS_SEC 1
J 0
(-3450 -725);
DISPLAY 1.021277 (-3450 -725);
DISPLAY INVISIBLE (-3450 -725);
FORCEPROP 1 LAST PATH I52
J 0
(-3450 -775);
DISPLAY 0.978723 (-3450 -775);
PAINT WHITE (-3450 -775);
DISPLAY INVISIBLE (-3450 -775);
FORCEADD Q_RES..1
(-3400 -975);
FORCEPROP 1 LAST PART_NUMBER CS12002FB06
J 0
(-3275 -1000);
DISPLAY 0.404255 (-3275 -1000);
DISPLAY INVISIBLE (-3275 -1000);
FORCEPROP 1 LAST VALUE 200
J 2
(-3200 -975);
DISPLAY 0.510638 (-3200 -975);
FORCEPROP 1 LAST TOLERANCE 1%
J 0
(-3175 -975);
DISPLAY 0.510638 (-3175 -975);
FORCEPROP 1 LAST MATERIAL CHIP
J 0
(-2925 -1000);
DISPLAY 0.404255 (-2925 -1000);
FORCEPROP 1 LAST WATTAGE 1/16W
J 2
(-2950 -1000);
DISPLAY 0.404255 (-2950 -1000);
FORCEPROP 1 LAST PACK_TYPE 0402LF
J 0
(-3100 -975);
DISPLAY 0.510638 (-3100 -975);
FORCEPROP 1 LAST $LOCATION R60
J 0
(-3575 -975);
DISPLAY 0.638298 (-3575 -975);
FORCEPROP 1 LASTPIN (-3500 -975) $PN 1
J 0
(-3488 -963);
DISPLAY 0.787234 (-3488 -963);
FORCEPROP 1 LASTPIN (-3300 -975) $PN 2
J 0
(-3338 -963);
DISPLAY 0.787234 (-3338 -963);
FORCEPROP 2 LAST CDS_LIB pure_quanta
J 0
(-3400 -975);
PAINT MONO (-3400 -975);
DISPLAY INVISIBLE (-3400 -975);
FORCEPROP 1 LAST $LOCATION R60
J 0
(-3450 -775);
DISPLAY 1.021277 (-3450 -775);
DISPLAY INVISIBLE (-3450 -775);
FORCEPROP 2 LAST CDS_LOCATION R60
J 0
(-3450 -775);
DISPLAY 1.021277 (-3450 -775);
DISPLAY INVISIBLE (-3450 -775);
FORCEPROP 2 LAST $SEC 1
J 0
(-3450 -775);
DISPLAY 0.680851 (-3450 -775);
PAINT MONO (-3450 -775);
DISPLAY INVISIBLE (-3450 -775);
FORCEPROP 2 LAST CDS_SEC 1
J 0
(-3450 -775);
DISPLAY 1.021277 (-3450 -775);
DISPLAY INVISIBLE (-3450 -775);
FORCEPROP 1 LAST PATH I53
J 0
(-3450 -825);
DISPLAY 0.978723 (-3450 -825);
PAINT WHITE (-3450 -825);
DISPLAY INVISIBLE (-3450 -825);
FORCEADD Q_RES..1
(-3400 -675);
FORCEPROP 1 LAST PART_NUMBER CS00002JB13
J 0
(-3275 -650);
DISPLAY 0.404255 (-3275 -650);
DISPLAY INVISIBLE (-3275 -650);
FORCEPROP 1 LAST VALUE 0
J 2
(-3250 -675);
DISPLAY 0.510638 (-3250 -675);
FORCEPROP 1 LAST TOLERANCE 5%
J 0
(-3175 -675);
DISPLAY 0.510638 (-3175 -675);
FORCEPROP 1 LAST MATERIAL CHIP
J 0
(-3275 -625);
DISPLAY 0.404255 (-3275 -625);
FORCEPROP 1 LAST WATTAGE 1/16W
J 2
(-3075 -625);
DISPLAY 0.404255 (-3075 -625);
FORCEPROP 1 LAST PACK_TYPE 0402LF
J 0
(-3100 -675);
DISPLAY 0.510638 (-3100 -675);
FORCEPROP 1 LAST $LOCATION R55
J 0
(-3575 -675);
DISPLAY 0.638298 (-3575 -675);
FORCEPROP 1 LASTPIN (-3500 -675) $PN 1
J 0
(-3488 -663);
DISPLAY 0.787234 (-3488 -663);
FORCEPROP 1 LASTPIN (-3300 -675) $PN 2
J 0
(-3338 -663);
DISPLAY 0.787234 (-3338 -663);
FORCEPROP 2 LAST CDS_LIB pure_quanta
J 0
(-3400 -675);
PAINT MONO (-3400 -675);
DISPLAY INVISIBLE (-3400 -675);
FORCEPROP 1 LAST $LOCATION R55
J 0
(-3450 -475);
DISPLAY 1.021277 (-3450 -475);
DISPLAY INVISIBLE (-3450 -475);
FORCEPROP 2 LAST CDS_LOCATION R55
J 0
(-3450 -475);
DISPLAY 1.021277 (-3450 -475);
DISPLAY INVISIBLE (-3450 -475);
FORCEPROP 2 LAST $SEC 1
J 0
(-3450 -475);
DISPLAY 0.680851 (-3450 -475);
PAINT MONO (-3450 -475);
DISPLAY INVISIBLE (-3450 -475);
FORCEPROP 2 LAST CDS_SEC 1
J 0
(-3450 -475);
DISPLAY 1.021277 (-3450 -475);
DISPLAY INVISIBLE (-3450 -475);
FORCEPROP 1 LAST PATH I54
J 0
(-3450 -525);
DISPLAY 0.978723 (-3450 -525);
PAINT WHITE (-3450 -525);
DISPLAY INVISIBLE (-3450 -525);
FORCEADD Q_RES..1
(-3400 -725);
FORCEPROP 1 LAST PART_NUMBER CS00002JB13
J 0
(-3275 -750);
DISPLAY 0.404255 (-3275 -750);
DISPLAY INVISIBLE (-3275 -750);
FORCEPROP 1 LAST VALUE 0
J 2
(-3250 -725);
DISPLAY 0.510638 (-3250 -725);
FORCEPROP 1 LAST TOLERANCE 5%
J 0
(-3175 -725);
DISPLAY 0.510638 (-3175 -725);
FORCEPROP 1 LAST PACK_TYPE 0402LF
J 0
(-3100 -725);
DISPLAY 0.510638 (-3100 -725);
FORCEPROP 1 LAST $LOCATION R56
J 0
(-3575 -725);
DISPLAY 0.638298 (-3575 -725);
FORCEPROP 1 LASTPIN (-3500 -725) $PN 1
J 0
(-3488 -713);
DISPLAY 0.787234 (-3488 -713);
FORCEPROP 1 LASTPIN (-3300 -725) $PN 2
J 0
(-3338 -713);
DISPLAY 0.787234 (-3338 -713);
FORCEPROP 2 LAST CDS_LIB pure_quanta
J 0
(-3400 -725);
PAINT MONO (-3400 -725);
DISPLAY INVISIBLE (-3400 -725);
FORCEPROP 1 LAST WATTAGE 1/16W
J 2
(-2950 -750);
DISPLAY 0.404255 (-2950 -750);
DISPLAY INVISIBLE (-2950 -750);
FORCEPROP 1 LAST MATERIAL CHIP
J 0
(-2925 -750);
DISPLAY 0.404255 (-2925 -750);
DISPLAY INVISIBLE (-2925 -750);
FORCEPROP 1 LAST $LOCATION R56
J 0
(-3450 -525);
DISPLAY 1.021277 (-3450 -525);
DISPLAY INVISIBLE (-3450 -525);
FORCEPROP 2 LAST CDS_LOCATION R56
J 0
(-3450 -525);
DISPLAY 1.021277 (-3450 -525);
DISPLAY INVISIBLE (-3450 -525);
FORCEPROP 2 LAST $SEC 1
J 0
(-3450 -525);
DISPLAY 0.680851 (-3450 -525);
PAINT MONO (-3450 -525);
DISPLAY INVISIBLE (-3450 -525);
FORCEPROP 2 LAST CDS_SEC 1
J 0
(-3450 -525);
DISPLAY 1.021277 (-3450 -525);
DISPLAY INVISIBLE (-3450 -525);
FORCEPROP 1 LAST PATH I55
J 0
(-3450 -575);
DISPLAY 0.978723 (-3450 -575);
PAINT WHITE (-3450 -575);
DISPLAY INVISIBLE (-3450 -575);
FORCEADD Q_RES..1
(-3400 -775);
FORCEPROP 1 LAST PART_NUMBER CS12002FB06
J 0
(-3275 -800);
DISPLAY 0.404255 (-3275 -800);
DISPLAY INVISIBLE (-3275 -800);
FORCEPROP 1 LAST VALUE 200
J 2
(-3200 -775);
DISPLAY 0.510638 (-3200 -775);
FORCEPROP 1 LAST TOLERANCE 1%
J 0
(-3175 -775);
DISPLAY 0.510638 (-3175 -775);
FORCEPROP 1 LAST WATTAGE 1/16W
J 2
(-2950 -800);
DISPLAY 0.404255 (-2950 -800);
FORCEPROP 1 LAST MATERIAL CHIP
J 0
(-2925 -800);
DISPLAY 0.404255 (-2925 -800);
FORCEPROP 1 LAST PACK_TYPE 0402LF
J 0
(-3100 -775);
DISPLAY 0.510638 (-3100 -775);
FORCEPROP 1 LAST $LOCATION R57
J 0
(-3575 -775);
DISPLAY 0.638298 (-3575 -775);
FORCEPROP 1 LASTPIN (-3500 -775) $PN 1
J 0
(-3488 -763);
DISPLAY 0.787234 (-3488 -763);
FORCEPROP 1 LASTPIN (-3300 -775) $PN 2
J 0
(-3338 -763);
DISPLAY 0.787234 (-3338 -763);
FORCEPROP 2 LAST CDS_LIB pure_quanta
J 0
(-3400 -775);
PAINT MONO (-3400 -775);
DISPLAY INVISIBLE (-3400 -775);
FORCEPROP 1 LAST $LOCATION R57
J 0
(-3450 -575);
DISPLAY 1.021277 (-3450 -575);
DISPLAY INVISIBLE (-3450 -575);
FORCEPROP 2 LAST CDS_LOCATION R57
J 0
(-3450 -575);
DISPLAY 1.021277 (-3450 -575);
DISPLAY INVISIBLE (-3450 -575);
FORCEPROP 2 LAST $SEC 1
J 0
(-3450 -575);
DISPLAY 0.680851 (-3450 -575);
PAINT MONO (-3450 -575);
DISPLAY INVISIBLE (-3450 -575);
FORCEPROP 2 LAST CDS_SEC 1
J 0
(-3450 -575);
DISPLAY 1.021277 (-3450 -575);
DISPLAY INVISIBLE (-3450 -575);
FORCEPROP 1 LAST PATH I56
J 0
(-3450 -625);
DISPLAY 0.978723 (-3450 -625);
PAINT WHITE (-3450 -625);
DISPLAY INVISIBLE (-3450 -625);
FORCEADD OFFPAGE..4
(-2000 -975);
FORCEPROP 2 LAST $XR1 296 
J 0
(-1724 -975);
DISPLAY 0.638298 (-1724 -975);
PAINT MONO (-1724 -975);
FORCEPROP 2 LAST $XR0 45 
J 0
(-1814 -975);
DISPLAY 0.638298 (-1814 -975);
PAINT MONO (-1814 -975);
FORCEPROP 2 LAST CDS_LIB standard
J 0
(-2000 -975);
PAINT MONO (-2000 -975);
DISPLAY INVISIBLE (-2000 -975);
FORCEPROP 1 LAST OFFPAGE TRUE
J 0
(-1675 -1100);
DISPLAY 1.170213 (-1675 -1100);
PAINT GREEN (-1675 -1100);
DISPLAY INVISIBLE (-1675 -1100);
FORCEPROP 1 LAST COMMENT_BODY TRUE
J 0
(-2025 -1075);
DISPLAY 1.170213 (-2025 -1075);
PAINT GREEN (-2025 -1075);
DISPLAY INVISIBLE (-2025 -1075);
FORCEPROP 2 LAST PATH I57
J 0
(-1825 -900);
DISPLAY 1.021277 (-1825 -900);
DISPLAY INVISIBLE (-1825 -900);
FORCEADD OFFPAGE..2
(-2000 -925);
FORCEPROP 2 LAST $XR0 296 
J 0
(-1811 -925);
DISPLAY 0.638298 (-1811 -925);
PAINT MONO (-1811 -925);
FORCEPROP 2 LAST CDS_LIB standard
J 0
(-2000 -925);
PAINT MONO (-2000 -925);
DISPLAY INVISIBLE (-2000 -925);
FORCEPROP 1 LAST OFFPAGE TRUE
J 0
(-1675 -1050);
DISPLAY 1.170213 (-1675 -1050);
PAINT GREEN (-1675 -1050);
DISPLAY INVISIBLE (-1675 -1050);
FORCEPROP 1 LAST COMMENT_BODY TRUE
J 0
(-2045 -1020);
DISPLAY 1.170213 (-2045 -1020);
PAINT GREEN (-2045 -1020);
DISPLAY INVISIBLE (-2045 -1020);
FORCEPROP 2 LAST PATH I58
J 0
(-1825 -850);
DISPLAY 1.021277 (-1825 -850);
DISPLAY INVISIBLE (-1825 -850);
FORCEADD OFFPAGE..3
(-2000 -875);
FORCEPROP 2 LAST $XR1 296 
J 0
(-1696 -875);
DISPLAY 0.638298 (-1696 -875);
PAINT MONO (-1696 -875);
FORCEPROP 2 LAST $XR0 45 
J 0
(-1786 -875);
DISPLAY 0.638298 (-1786 -875);
PAINT MONO (-1786 -875);
FORCEPROP 2 LAST CDS_LIB standard
J 0
(-2000 -875);
PAINT MONO (-2000 -875);
DISPLAY INVISIBLE (-2000 -875);
FORCEPROP 1 LAST OFFPAGE TRUE
J 0
(-1675 -1000);
DISPLAY 1.170213 (-1675 -1000);
PAINT GREEN (-1675 -1000);
DISPLAY INVISIBLE (-1675 -1000);
FORCEPROP 1 LAST COMMENT_BODY TRUE
J 0
(-2050 -975);
DISPLAY 1.170213 (-2050 -975);
PAINT GREEN (-2050 -975);
DISPLAY INVISIBLE (-2050 -975);
FORCEPROP 2 LAST PATH I59
J 0
(-1800 -800);
DISPLAY 1.021277 (-1800 -800);
DISPLAY INVISIBLE (-1800 -800);
FORCEADD OFFPAGE..4
(-2000 -775);
FORCEPROP 2 LAST $XR2 292 
J 0
(-1604 -775);
DISPLAY 0.638298 (-1604 -775);
PAINT MONO (-1604 -775);
FORCEPROP 2 LAST $XR1 284 
J 0
(-1724 -775);
DISPLAY 0.638298 (-1724 -775);
PAINT MONO (-1724 -775);
FORCEPROP 2 LAST $XR0 45 
J 0
(-1814 -775);
DISPLAY 0.638298 (-1814 -775);
PAINT MONO (-1814 -775);
FORCEPROP 2 LAST CDS_LIB standard
J 0
(-2000 -775);
PAINT MONO (-2000 -775);
DISPLAY INVISIBLE (-2000 -775);
FORCEPROP 1 LAST OFFPAGE TRUE
J 0
(-1675 -900);
DISPLAY 1.170213 (-1675 -900);
PAINT GREEN (-1675 -900);
DISPLAY INVISIBLE (-1675 -900);
FORCEPROP 1 LAST COMMENT_BODY TRUE
J 0
(-2025 -875);
DISPLAY 1.170213 (-2025 -875);
PAINT GREEN (-2025 -875);
DISPLAY INVISIBLE (-2025 -875);
FORCEPROP 2 LAST PATH I60
J 0
(-1825 -700);
DISPLAY 1.021277 (-1825 -700);
DISPLAY INVISIBLE (-1825 -700);
FORCEADD OFFPAGE..2
(-2000 -725);
FORCEPROP 2 LAST $XR1 292 
J 0
(-1691 -725);
DISPLAY 0.638298 (-1691 -725);
PAINT MONO (-1691 -725);
FORCEPROP 2 LAST $XR0 284 
J 0
(-1811 -725);
DISPLAY 0.638298 (-1811 -725);
PAINT MONO (-1811 -725);
FORCEPROP 2 LAST CDS_LIB standard
J 0
(-2000 -725);
PAINT MONO (-2000 -725);
DISPLAY INVISIBLE (-2000 -725);
FORCEPROP 1 LAST OFFPAGE TRUE
J 0
(-1675 -850);
DISPLAY 1.170213 (-1675 -850);
PAINT GREEN (-1675 -850);
DISPLAY INVISIBLE (-1675 -850);
FORCEPROP 1 LAST COMMENT_BODY TRUE
J 0
(-2045 -820);
DISPLAY 1.170213 (-2045 -820);
PAINT GREEN (-2045 -820);
DISPLAY INVISIBLE (-2045 -820);
FORCEPROP 2 LAST PATH I61
J 0
(-1825 -650);
DISPLAY 1.021277 (-1825 -650);
DISPLAY INVISIBLE (-1825 -650);
FORCEADD OFFPAGE..3
(-2000 -675);
FORCEPROP 2 LAST $XR2 292 
J 0
(-1576 -675);
DISPLAY 0.638298 (-1576 -675);
PAINT MONO (-1576 -675);
FORCEPROP 2 LAST $XR1 284 
J 0
(-1696 -675);
DISPLAY 0.638298 (-1696 -675);
PAINT MONO (-1696 -675);
FORCEPROP 2 LAST $XR0 45 
J 0
(-1786 -675);
DISPLAY 0.638298 (-1786 -675);
PAINT MONO (-1786 -675);
FORCEPROP 2 LAST CDS_LIB standard
J 0
(-2000 -675);
PAINT MONO (-2000 -675);
DISPLAY INVISIBLE (-2000 -675);
FORCEPROP 1 LAST OFFPAGE TRUE
J 0
(-1675 -800);
DISPLAY 1.170213 (-1675 -800);
PAINT GREEN (-1675 -800);
DISPLAY INVISIBLE (-1675 -800);
FORCEPROP 1 LAST COMMENT_BODY TRUE
J 0
(-2050 -775);
DISPLAY 1.170213 (-2050 -775);
PAINT GREEN (-2050 -775);
DISPLAY INVISIBLE (-2050 -775);
FORCEPROP 2 LAST PATH I62
J 0
(-1800 -600);
DISPLAY 1.021277 (-1800 -600);
DISPLAY INVISIBLE (-1800 -600);
FORCEADD OFFPAGE..2
R 2
(-4400 -4925);
FORCEPROP 2 LAST $XR1 296 
J 0
(-4774 -4925);
DISPLAY 0.638298 (-4774 -4925);
PAINT MONO (-4774 -4925);
FORCEPROP 2 LAST $XR0 45 
J 0
(-4654 -4925);
DISPLAY 0.638298 (-4654 -4925);
PAINT MONO (-4654 -4925);
FORCEPROP 2 LAST CDS_LIB standard
J 0
(-4400 -4925);
PAINT MONO (-4400 -4925);
DISPLAY INVISIBLE (-4400 -4925);
FORCEPROP 1 LAST OFFPAGE TRUE
J 2
(-4725 -5050);
DISPLAY 0.872340 (-4725 -5050);
DISPLAY INVISIBLE (-4725 -5050);
FORCEPROP 1 LAST COMMENT_BODY TRUE
J 2
(-4355 -5020);
DISPLAY 0.872340 (-4355 -5020);
PAINT GREEN (-4355 -5020);
DISPLAY INVISIBLE (-4355 -5020);
FORCEPROP 2 LAST PATH I67
J 0
(-4650 -4875);
DISPLAY 1.021277 (-4650 -4875);
DISPLAY INVISIBLE (-4650 -4875);
FORCEADD Q_RES..1
(-3075 -4925);
FORCEPROP 1 LAST PART_NUMBER CS11002FB07
J 0
(-3250 -4875);
DISPLAY 0.510638 (-3250 -4875);
DISPLAY INVISIBLE (-3250 -4875);
FORCEPROP 1 LAST MATERIAL CHIP
J 0
(-2750 -4925);
DISPLAY 0.638298 (-2750 -4925);
FORCEPROP 1 LAST PACK_TYPE 0402LF
J 0
(-3250 -4825);
DISPLAY 0.510638 (-3250 -4825);
FORCEPROP 1 LAST TOLERANCE 1%
J 0
(-2825 -4925);
DISPLAY 0.638298 (-2825 -4925);
FORCEPROP 1 LAST VALUE 100
J 2
(-2875 -4925);
DISPLAY 0.638298 (-2875 -4925);
FORCEPROP 1 LAST WATTAGE 1/16W
J 2
(-2925 -4825);
DISPLAY 0.510638 (-2925 -4825);
FORCEPROP 1 LAST $LOCATION R559
J 0
(-3325 -4925);
DISPLAY 0.808511 (-3325 -4925);
FORCEPROP 1 LASTPIN (-3175 -4925) $PN 1
J 0
(-3163 -4913);
DISPLAY 0.787234 (-3163 -4913);
FORCEPROP 1 LASTPIN (-2975 -4925) $PN 2
J 0
(-3013 -4913);
DISPLAY 0.787234 (-3013 -4913);
FORCEPROP 2 LAST CDS_LIB pure_quanta
J 0
(-3075 -4925);
PAINT MONO (-3075 -4925);
DISPLAY INVISIBLE (-3075 -4925);
FORCEPROP 2 LAST CDS_LOCATION R559
J 0
(-3125 -4725);
DISPLAY 1.021277 (-3125 -4725);
DISPLAY INVISIBLE (-3125 -4725);
FORCEPROP 2 LAST $SEC 1
J 0
(-3125 -4725);
DISPLAY 0.680851 (-3125 -4725);
PAINT MONO (-3125 -4725);
DISPLAY INVISIBLE (-3125 -4725);
FORCEPROP 2 LAST CDS_SEC 1
J 0
(-3125 -4725);
DISPLAY 1.021277 (-3125 -4725);
DISPLAY INVISIBLE (-3125 -4725);
FORCEPROP 1 LAST PATH I69
J 0
(-3125 -4775);
DISPLAY 0.978723 (-3125 -4775);
PAINT WHITE (-3125 -4775);
DISPLAY INVISIBLE (-3125 -4775);
FORCEADD OFFPAGE..1
(-8075 -3025);
FORCEPROP 2 LAST $XR0 125 
J 0
(-8357 -3025);
DISPLAY 0.638298 (-8357 -3025);
PAINT MONO (-8357 -3025);
FORCEPROP 2 LAST CDS_LIB standard
J 0
(-8075 -3025);
PAINT MONO (-8075 -3025);
DISPLAY INVISIBLE (-8075 -3025);
FORCEPROP 1 LAST OFFPAGE TRUE
J 0
(-7750 -3150);
DISPLAY 0.872340 (-7750 -3150);
DISPLAY INVISIBLE (-7750 -3150);
FORCEPROP 1 LAST COMMENT_BODY TRUE
J 0
(-7950 -3125);
DISPLAY 0.872340 (-7950 -3125);
PAINT GREEN (-7950 -3125);
DISPLAY INVISIBLE (-7950 -3125);
FORCEPROP 2 LAST PATH I7
J 0
(-8025 -2950);
DISPLAY 1.021277 (-8025 -2950);
DISPLAY INVISIBLE (-8025 -2950);
FORCEADD Q_RES..1
(-3075 -5125);
FORCEPROP 1 LAST PART_NUMBER CS04992FB07
J 0
(-3225 -5075);
DISPLAY 0.638298 (-3225 -5075);
DISPLAY INVISIBLE (-3225 -5075);
FORCEPROP 1 LAST WATTAGE 1/16W
J 2
(-2875 -5025);
DISPLAY 0.638298 (-2875 -5025);
FORCEPROP 1 LAST PACK_TYPE 0402LF
J 0
(-3225 -5025);
DISPLAY 0.638298 (-3225 -5025);
FORCEPROP 1 LAST TOLERANCE 1%
J 0
(-2825 -5125);
DISPLAY 0.638298 (-2825 -5125);
FORCEPROP 1 LAST MATERIAL CHIP
J 0
(-2750 -5125);
DISPLAY 0.638298 (-2750 -5125);
FORCEPROP 1 LAST VALUE 49.9
J 2
(-2850 -5125);
DISPLAY 0.638298 (-2850 -5125);
FORCEPROP 1 LAST $LOCATION R560
J 0
(-3325 -5125);
DISPLAY 0.808511 (-3325 -5125);
FORCEPROP 1 LASTPIN (-3175 -5125) $PN 1
J 0
(-3163 -5113);
DISPLAY 0.787234 (-3163 -5113);
FORCEPROP 1 LASTPIN (-2975 -5125) $PN 2
J 0
(-3013 -5113);
DISPLAY 0.787234 (-3013 -5113);
FORCEPROP 2 LAST CDS_LIB pure_quanta
J 0
(-3075 -5125);
PAINT MONO (-3075 -5125);
DISPLAY INVISIBLE (-3075 -5125);
FORCEPROP 2 LAST CDS_LOCATION R560
J 0
(-3125 -4925);
DISPLAY 1.021277 (-3125 -4925);
DISPLAY INVISIBLE (-3125 -4925);
FORCEPROP 2 LAST $SEC 1
J 0
(-3125 -4925);
DISPLAY 0.680851 (-3125 -4925);
PAINT MONO (-3125 -4925);
DISPLAY INVISIBLE (-3125 -4925);
FORCEPROP 2 LAST CDS_SEC 1
J 0
(-3125 -4925);
DISPLAY 1.021277 (-3125 -4925);
DISPLAY INVISIBLE (-3125 -4925);
FORCEPROP 1 LAST PATH I70
J 0
(-3125 -4975);
DISPLAY 0.978723 (-3125 -4975);
PAINT WHITE (-3125 -4975);
DISPLAY INVISIBLE (-3125 -4975);
FORCEADD OFFPAGE..2
R 2
(-4400 -4725);
FORCEPROP 2 LAST $XR2 45 
J 0
(-4895 -4725);
DISPLAY 0.638298 (-4895 -4725);
PAINT MONO (-4895 -4725);
FORCEPROP 2 LAST $XR1 292 
J 0
(-4805 -4725);
DISPLAY 0.638298 (-4805 -4725);
PAINT MONO (-4805 -4725);
FORCEPROP 2 LAST $XR0 284 
J 0
(-4685 -4725);
DISPLAY 0.638298 (-4685 -4725);
PAINT MONO (-4685 -4725);
FORCEPROP 2 LAST CDS_LIB standard
J 0
(-4400 -4725);
PAINT MONO (-4400 -4725);
DISPLAY INVISIBLE (-4400 -4725);
FORCEPROP 1 LAST OFFPAGE TRUE
J 2
(-4725 -4850);
DISPLAY 0.872340 (-4725 -4850);
DISPLAY INVISIBLE (-4725 -4850);
FORCEPROP 1 LAST COMMENT_BODY TRUE
J 2
(-4355 -4820);
DISPLAY 0.872340 (-4355 -4820);
PAINT GREEN (-4355 -4820);
DISPLAY INVISIBLE (-4355 -4820);
FORCEPROP 2 LAST PATH I71
J 0
(-4650 -4675);
DISPLAY 1.021277 (-4650 -4675);
DISPLAY INVISIBLE (-4650 -4675);
FORCEADD OFFPAGE..2
R 2
(-4400 -4525);
FORCEPROP 2 LAST $XR2 292 
J 0
(-4894 -4525);
DISPLAY 0.638298 (-4894 -4525);
PAINT MONO (-4894 -4525);
FORCEPROP 2 LAST $XR1 284 
J 0
(-4774 -4525);
DISPLAY 0.638298 (-4774 -4525);
PAINT MONO (-4774 -4525);
FORCEPROP 2 LAST $XR0 45 
J 0
(-4654 -4525);
DISPLAY 0.638298 (-4654 -4525);
PAINT MONO (-4654 -4525);
FORCEPROP 2 LAST CDS_LIB standard
J 0
(-4400 -4525);
PAINT MONO (-4400 -4525);
DISPLAY INVISIBLE (-4400 -4525);
FORCEPROP 1 LAST OFFPAGE TRUE
J 2
(-4725 -4650);
DISPLAY 0.872340 (-4725 -4650);
DISPLAY INVISIBLE (-4725 -4650);
FORCEPROP 1 LAST COMMENT_BODY TRUE
J 2
(-4355 -4620);
DISPLAY 0.872340 (-4355 -4620);
PAINT GREEN (-4355 -4620);
DISPLAY INVISIBLE (-4355 -4620);
FORCEPROP 2 LAST PATH I72
J 0
(-4650 -4475);
DISPLAY 1.021277 (-4650 -4475);
DISPLAY INVISIBLE (-4650 -4475);
FORCEADD Q_RES..1
(-3075 -4725);
FORCEPROP 1 LAST PART_NUMBER CS04992FB07
J 0
(-3225 -4675);
DISPLAY 0.638298 (-3225 -4675);
DISPLAY INVISIBLE (-3225 -4675);
FORCEPROP 1 LAST TOLERANCE 1%
J 0
(-2825 -4725);
DISPLAY 0.638298 (-2825 -4725);
FORCEPROP 1 LAST MATERIAL CHIP
J 0
(-2750 -4725);
DISPLAY 0.638298 (-2750 -4725);
FORCEPROP 1 LAST PACK_TYPE 0402LF
J 0
(-3225 -4625);
DISPLAY 0.638298 (-3225 -4625);
FORCEPROP 1 LAST WATTAGE 1/16W
J 2
(-2875 -4625);
DISPLAY 0.638298 (-2875 -4625);
FORCEPROP 1 LAST VALUE 49.9
J 2
(-2850 -4725);
DISPLAY 0.638298 (-2850 -4725);
FORCEPROP 1 LAST $LOCATION R558
J 0
(-3325 -4725);
DISPLAY 0.808511 (-3325 -4725);
FORCEPROP 1 LASTPIN (-3175 -4725) $PN 1
J 0
(-3163 -4713);
DISPLAY 0.787234 (-3163 -4713);
FORCEPROP 1 LASTPIN (-2975 -4725) $PN 2
J 0
(-3013 -4713);
DISPLAY 0.787234 (-3013 -4713);
FORCEPROP 2 LAST CDS_LIB pure_quanta
J 0
(-3075 -4725);
PAINT MONO (-3075 -4725);
DISPLAY INVISIBLE (-3075 -4725);
FORCEPROP 2 LAST CDS_LOCATION R558
J 0
(-3125 -4525);
DISPLAY 1.021277 (-3125 -4525);
DISPLAY INVISIBLE (-3125 -4525);
FORCEPROP 2 LAST $SEC 1
J 0
(-3125 -4525);
DISPLAY 0.680851 (-3125 -4525);
PAINT MONO (-3125 -4525);
DISPLAY INVISIBLE (-3125 -4525);
FORCEPROP 2 LAST CDS_SEC 1
J 0
(-3125 -4525);
DISPLAY 1.021277 (-3125 -4525);
DISPLAY INVISIBLE (-3125 -4525);
FORCEPROP 1 LAST PATH I73
J 0
(-3125 -4575);
DISPLAY 0.978723 (-3125 -4575);
PAINT WHITE (-3125 -4575);
DISPLAY INVISIBLE (-3125 -4575);
FORCEADD Q_RES..1
(-3075 -4525);
FORCEPROP 1 LAST PART_NUMBER CS11002FB07
J 0
(-3250 -4475);
DISPLAY 0.510638 (-3250 -4475);
DISPLAY INVISIBLE (-3250 -4475);
FORCEPROP 1 LAST MATERIAL CHIP
J 0
(-2750 -4525);
DISPLAY 0.638298 (-2750 -4525);
FORCEPROP 1 LAST TOLERANCE 1%
J 0
(-2825 -4525);
DISPLAY 0.638298 (-2825 -4525);
FORCEPROP 1 LAST PACK_TYPE 0402LF
J 0
(-3250 -4425);
DISPLAY 0.510638 (-3250 -4425);
FORCEPROP 1 LAST WATTAGE 1/16W
J 2
(-2925 -4425);
DISPLAY 0.510638 (-2925 -4425);
FORCEPROP 1 LAST VALUE 100
J 2
(-2875 -4525);
DISPLAY 0.638298 (-2875 -4525);
FORCEPROP 1 LAST $LOCATION R557
J 0
(-3325 -4525);
DISPLAY 0.808511 (-3325 -4525);
FORCEPROP 1 LASTPIN (-3175 -4525) $PN 1
J 0
(-3163 -4513);
DISPLAY 0.787234 (-3163 -4513);
FORCEPROP 1 LASTPIN (-2975 -4525) $PN 2
J 0
(-3013 -4513);
DISPLAY 0.787234 (-3013 -4513);
FORCEPROP 2 LAST CDS_LIB pure_quanta
J 0
(-3075 -4525);
PAINT MONO (-3075 -4525);
DISPLAY INVISIBLE (-3075 -4525);
FORCEPROP 2 LAST CDS_LOCATION R557
J 0
(-3125 -4325);
DISPLAY 1.021277 (-3125 -4325);
DISPLAY INVISIBLE (-3125 -4325);
FORCEPROP 2 LAST $SEC 1
J 0
(-3125 -4325);
DISPLAY 0.680851 (-3125 -4325);
PAINT MONO (-3125 -4325);
DISPLAY INVISIBLE (-3125 -4325);
FORCEPROP 2 LAST CDS_SEC 1
J 0
(-3125 -4325);
DISPLAY 1.021277 (-3125 -4325);
DISPLAY INVISIBLE (-3125 -4325);
FORCEPROP 1 LAST PATH I74
J 0
(-3125 -4375);
DISPLAY 0.978723 (-3125 -4375);
PAINT WHITE (-3125 -4375);
DISPLAY INVISIBLE (-3125 -4375);
FORCEADD UNIVERSAL_POWER..1
(-2525 -4300);
FORCEPROP 3 LASTPIN (-2525 -4350) SIG_NAME PVNN_TERM_CPU1\g
J 0
(-2515 -4340);
DISPLAY 0.659574 (-2515 -4340);
PAINT MONO (-2515 -4340);
DISPLAY INVISIBLE (-2515 -4340);
FORCEPROP 1 LAST HDL_POWER PVNN_TERM_CPU1
J 1
(-2525 -4250);
DISPLAY 0.872340 (-2525 -4250);
PAINT GREEN (-2525 -4250);
FORCEPROP 2 LAST CDS_LIB logical_power
J 0
(-2525 -4300);
PAINT MONO (-2525 -4300);
DISPLAY INVISIBLE (-2525 -4300);
FORCEPROP 1 LAST PATH I75
J 0
(-2475 -4275);
DISPLAY 0.872340 (-2475 -4275);
PAINT AQUA (-2475 -4275);
DISPLAY INVISIBLE (-2475 -4275);
FORCEADD OFFPAGE..2
R 2
(-4400 -5125);
FORCEPROP 2 LAST $XR1 45 
J 0
(-4775 -5125);
DISPLAY 0.638298 (-4775 -5125);
PAINT MONO (-4775 -5125);
FORCEPROP 2 LAST $XR0 296 
J 0
(-4685 -5125);
DISPLAY 0.638298 (-4685 -5125);
PAINT MONO (-4685 -5125);
FORCEPROP 2 LAST CDS_LIB standard
J 0
(-4400 -5125);
PAINT MONO (-4400 -5125);
DISPLAY INVISIBLE (-4400 -5125);
FORCEPROP 1 LAST OFFPAGE TRUE
J 2
(-4725 -5250);
DISPLAY 0.872340 (-4725 -5250);
DISPLAY INVISIBLE (-4725 -5250);
FORCEPROP 1 LAST COMMENT_BODY TRUE
J 2
(-4355 -5220);
DISPLAY 0.872340 (-4355 -5220);
PAINT GREEN (-4355 -5220);
DISPLAY INVISIBLE (-4355 -5220);
FORCEPROP 2 LAST PATH I78
J 0
(-4675 -5075);
DISPLAY 1.021277 (-4675 -5075);
DISPLAY INVISIBLE (-4675 -5075);
FORCEADD OFFPAGE..1
(-9625 -875);
FORCEPROP 2 LAST $XR0 236 
J 0
(-9877 -875);
DISPLAY 0.638298 (-9877 -875);
PAINT MONO (-9877 -875);
FORCEPROP 2 LAST CDS_LIB standard
J 0
(-9625 -875);
PAINT MONO (-9625 -875);
DISPLAY INVISIBLE (-9625 -875);
FORCEPROP 1 LAST OFFPAGE TRUE
J 0
(-9300 -1000);
DISPLAY 0.872340 (-9300 -1000);
DISPLAY INVISIBLE (-9300 -1000);
FORCEPROP 1 LAST COMMENT_BODY TRUE
J 0
(-9500 -975);
DISPLAY 0.872340 (-9500 -975);
PAINT GREEN (-9500 -975);
DISPLAY INVISIBLE (-9500 -975);
FORCEPROP 2 LAST PATH I79
J 0
(-9900 -825);
DISPLAY 1.021277 (-9900 -825);
DISPLAY INVISIBLE (-9900 -825);
FORCEADD OFFPAGE..1
(-8075 -2925);
FORCEPROP 2 LAST $XR0 125 
J 0
(-8357 -2925);
DISPLAY 0.638298 (-8357 -2925);
PAINT MONO (-8357 -2925);
FORCEPROP 2 LAST CDS_LIB standard
J 0
(-8075 -2925);
PAINT MONO (-8075 -2925);
DISPLAY INVISIBLE (-8075 -2925);
FORCEPROP 1 LAST OFFPAGE TRUE
J 0
(-7750 -3050);
DISPLAY 0.872340 (-7750 -3050);
DISPLAY INVISIBLE (-7750 -3050);
FORCEPROP 1 LAST COMMENT_BODY TRUE
J 0
(-7950 -3025);
DISPLAY 0.872340 (-7950 -3025);
PAINT GREEN (-7950 -3025);
DISPLAY INVISIBLE (-7950 -3025);
FORCEPROP 2 LAST PATH I8
J 0
(-8025 -2850);
DISPLAY 1.021277 (-8025 -2850);
DISPLAY INVISIBLE (-8025 -2850);
FORCEADD Q_RES..1
(-8475 -875);
FORCEPROP 1 LAST PART_NUMBER CS03322FB03
J 0
(-8600 -825);
DISPLAY 0.404255 (-8600 -825);
DISPLAY INVISIBLE (-8600 -825);
FORCEPROP 1 LAST PACK_TYPE 0402LF
J 0
(-8600 -775);
DISPLAY 0.404255 (-8600 -775);
FORCEPROP 1 LAST TOLERANCE 1%
J 0
(-8250 -875);
DISPLAY 0.404255 (-8250 -875);
FORCEPROP 1 LAST MATERIAL CHIP
J 0
(-8175 -875);
DISPLAY 0.404255 (-8175 -875);
FORCEPROP 1 LAST WATTAGE 1/16W
J 2
(-8375 -775);
DISPLAY 0.404255 (-8375 -775);
FORCEPROP 1 LAST VALUE 33.2
J 2
(-8275 -875);
DISPLAY 0.404255 (-8275 -875);
FORCEPROP 1 LAST $LOCATION R1934
J 0
(-8700 -875);
DISPLAY 0.638298 (-8700 -875);
FORCEPROP 1 LASTPIN (-8575 -875) $PN 1
J 0
(-8563 -863);
DISPLAY 0.787234 (-8563 -863);
PAINT MONO (-8563 -863);
FORCEPROP 1 LASTPIN (-8375 -875) $PN 2
J 0
(-8413 -863);
DISPLAY 0.787234 (-8413 -863);
PAINT MONO (-8413 -863);
FORCEPROP 2 LAST CDS_LIB pure_quanta
J 0
(-8475 -875);
DISPLAY INVISIBLE (-8475 -875);
FORCEPROP 0 LAST CDS_LOCATION R1934
J 0
(-8375 -750);
DISPLAY 1.021277 (-8375 -750);
DISPLAY INVISIBLE (-8375 -750);
FORCEPROP 0 LAST $SEC 1
J 0
(-8375 -750);
DISPLAY 0.680851 (-8375 -750);
PAINT MONO (-8375 -750);
DISPLAY INVISIBLE (-8375 -750);
FORCEPROP 0 LAST CDS_SEC 1
J 0
(-8375 -750);
DISPLAY 1.021277 (-8375 -750);
DISPLAY INVISIBLE (-8375 -750);
FORCEPROP 1 LAST PATH I81
J 0
(-8525 -725);
DISPLAY 0.978723 (-8525 -725);
PAINT WHITE (-8525 -725);
DISPLAY INVISIBLE (-8525 -725);
FORCEADD Q_RES..1
(-8475 -925);
FORCEPROP 1 LAST PART_NUMBER CS03322FB03
J 0
(-8600 -875);
DISPLAY 0.510638 (-8600 -875);
DISPLAY INVISIBLE (-8600 -875);
FORCEPROP 1 LAST MATERIAL CHIP
J 0
(-8175 -925);
DISPLAY 0.404255 (-8175 -925);
FORCEPROP 1 LAST TOLERANCE 1%
J 0
(-8250 -925);
DISPLAY 0.404255 (-8250 -925);
FORCEPROP 1 LAST VALUE 33.2
J 2
(-8275 -925);
DISPLAY 0.404255 (-8275 -925);
FORCEPROP 1 LAST $LOCATION R1935
J 0
(-8700 -925);
DISPLAY 0.638298 (-8700 -925);
FORCEPROP 1 LASTPIN (-8575 -925) $PN 1
J 0
(-8563 -913);
DISPLAY 0.787234 (-8563 -913);
PAINT MONO (-8563 -913);
FORCEPROP 1 LASTPIN (-8375 -925) $PN 2
J 0
(-8413 -913);
DISPLAY 0.787234 (-8413 -913);
PAINT MONO (-8413 -913);
FORCEPROP 1 LAST WATTAGE 1/16W
J 2
(-8250 -825);
DISPLAY 0.510638 (-8250 -825);
DISPLAY INVISIBLE (-8250 -825);
FORCEPROP 1 LAST PACK_TYPE 0402LF
J 0
(-8600 -825);
DISPLAY 0.510638 (-8600 -825);
DISPLAY INVISIBLE (-8600 -825);
FORCEPROP 2 LAST CDS_LIB pure_quanta
J 0
(-8475 -925);
DISPLAY INVISIBLE (-8475 -925);
FORCEPROP 0 LAST CDS_LOCATION R1935
J 0
(-8725 -875);
DISPLAY 1.021277 (-8725 -875);
DISPLAY INVISIBLE (-8725 -875);
FORCEPROP 0 LAST $SEC 1
J 0
(-8725 -875);
DISPLAY 0.680851 (-8725 -875);
PAINT MONO (-8725 -875);
DISPLAY INVISIBLE (-8725 -875);
FORCEPROP 0 LAST CDS_SEC 1
J 0
(-8725 -875);
DISPLAY 1.021277 (-8725 -875);
DISPLAY INVISIBLE (-8725 -875);
FORCEPROP 1 LAST PATH I82
J 0
(-8525 -775);
DISPLAY 0.978723 (-8525 -775);
PAINT WHITE (-8525 -775);
DISPLAY INVISIBLE (-8525 -775);
FORCEADD OFFPAGE..3
R 2
(-9625 -925);
FORCEPROP 2 LAST $XR0 236 
J 0
(-9905 -925);
DISPLAY 0.638298 (-9905 -925);
PAINT MONO (-9905 -925);
FORCEPROP 2 LAST CDS_LIB standard
J 0
(-9625 -925);
DISPLAY INVISIBLE (-9625 -925);
FORCEPROP 1 LAST OFFPAGE TRUE
J 2
(-9950 -1050);
DISPLAY 0.872340 (-9950 -1050);
DISPLAY INVISIBLE (-9950 -1050);
FORCEPROP 1 LAST COMMENT_BODY TRUE
J 2
(-9575 -1025);
DISPLAY 0.872340 (-9575 -1025);
PAINT GREEN (-9575 -1025);
DISPLAY INVISIBLE (-9575 -1025);
FORCEPROP 2 LAST PATH I83
J 0
(-9950 -875);
DISPLAY 1.021277 (-9950 -875);
DISPLAY INVISIBLE (-9950 -875);
FORCEADD OFFPAGE..1
(-8075 -2975);
FORCEPROP 2 LAST $XR0 125 
J 0
(-8357 -2975);
DISPLAY 0.638298 (-8357 -2975);
PAINT MONO (-8357 -2975);
FORCEPROP 2 LAST CDS_LIB standard
J 0
(-8075 -2975);
PAINT MONO (-8075 -2975);
DISPLAY INVISIBLE (-8075 -2975);
FORCEPROP 1 LAST OFFPAGE TRUE
J 0
(-7750 -3100);
DISPLAY 0.872340 (-7750 -3100);
DISPLAY INVISIBLE (-7750 -3100);
FORCEPROP 1 LAST COMMENT_BODY TRUE
J 0
(-7950 -3075);
DISPLAY 0.872340 (-7950 -3075);
PAINT GREEN (-7950 -3075);
DISPLAY INVISIBLE (-7950 -3075);
FORCEPROP 2 LAST PATH I9
J 0
(-8025 -2900);
DISPLAY 1.021277 (-8025 -2900);
DISPLAY INVISIBLE (-8025 -2900);
FORCEADD QUANTA_TITLE_BLOCK_C..1
(-1050 -6250);
FORCEPROP 0 LAST CDS_CON_LAST_MODIFIED Fri Aug 25 14:00:27 2023
J 0
(-2935 -6235);
PAINT MONO (-2935 -6235);
DISPLAY INVISIBLE (-2935 -6235);
FORCEPROP 1 LAST CUSTOM_TXT_CDS <CON_LAST_MODIFIED>
J 0
(-2935 -6235);
DISPLAY 0.978723 (-2935 -6235);
FORCEPROP 2 LAST CUSTOM_TXT_CDS <XR_PAGE_TITLE>
J 0
(-8940 -1000);
DISPLAY 0.638298 (-8940 -1000);
PAINT PINK (-8940 -1000);
DISPLAY INVISIBLE (-8940 -1000);
FORCEPROP 2 LAST CUSTOM_TXT_CDS <Q_NUMBER>
J 0
(-2453 -6147);
DISPLAY 1.212766 (-2453 -6147);
FORCEPROP 2 LAST CUSTOM_TXT_CDS EAGLE_STERAM
J 0
(-3432 -6148);
DISPLAY 1.212766 (-3432 -6148);
FORCEPROP 1 LAST CUSTOM_TXT_CDS <NAME_2>
J 0
(-4225 -6200);
FORCEPROP 1 LAST CUSTOM_TXT_CDS <NAME_1>
J 0
(-4225 -6075);
FORCEPROP 1 LAST CUSTOM_TXT_CDS <Q_PROJ>
J 0
(-3432 -6148);
DISPLAY 1.212766 (-3432 -6148);
FORCEPROP 1 LAST CUSTOM_TXT_CDS <Q_REV>
J 0
(-1234 -6147);
DISPLAY 1.212766 (-1234 -6147);
FORCEPROP 1 LAST CUSTOM_TXT_CDS <CON_PAGE_NUM> OF <CON_TOTAL_PAGES>
J 0
(-1496 -6232);
DISPLAY 0.978723 (-1496 -6232);
FORCEPROP 1 LAST Q_TITLE SPR CPU1 MISC:SMBUS/SVID/ERRORS(2/30)
J 0
(-10416 -6224);
DISPLAY 1.957447 (-10416 -6224);
PAINT GREEN (-10416 -6224);
FORCEPROP 1 LAST Q_DEPT 
J 1
(-4813 -6201);
DISPLAY 1.957447 (-4813 -6201);
PAINT GREEN (-4813 -6201);
FORCEPROP 2 LAST PAGE_BORDER TRUE
J 0
(-8940 -1000);
DISPLAY 0.638298 (-8940 -1000);
PAINT PINK (-8940 -1000);
DISPLAY INVISIBLE (-8940 -1000);
FORCEPROP 1 LAST CDS_LMAN_SYM_OUTLINE -9475,6775,100,-125
J 0
(-1050 -6250);
DISPLAY 0.468085 (-1050 -6250);
PAINT GREEN (-1050 -6250);
DISPLAY INVISIBLE (-1050 -6250);
FORCEPROP 2 LAST CDS_LIB pure_quanta
J 0
(-1050 -6250);
PAINT MONO (-1050 -6250);
DISPLAY INVISIBLE (-1050 -6250);
FORCEPROP 2 LAST CDS_XR_PAGE_TITLE CR-45 : @S9S_MB_2U_LIB.S9S_MB_2U(SCH_1):PAGE45
J 0
(-8940 -1000);
DISPLAY 0.638298 (-8940 -1000);
PAINT PINK (-8940 -1000);
DISPLAY INVISIBLE (-8940 -1000);
FORCEPROP 1 LAST COMMENT_BODY TRUE
J 0
(-1038 -6263);
DISPLAY 0.978723 (-1038 -6263);
PAINT GREEN (-1038 -6263);
DISPLAY INVISIBLE (-1038 -6263);
WIRE 16 -1 (-2525 -4350)(-2525 -4525);
WIRE 16 -1 (-6975 -1875)(-8025 -1875);
FORCEPROP 2 LAST SIG_NAME TP_H_CPU1_PMSYNC_PCH_INTRP_R
J 0
(-7962 -1866);
DISPLAY 0.553191 (-7962 -1866);
PAINT WHITE (-7962 -1866);
WIRE 16 -1 (-6975 -1825)(-8025 -1825);
FORCEPROP 2 LAST SIG_NAME CPU1_RSVD<107>
J 0
(-7962 -1816);
DISPLAY 0.553191 (-7962 -1816);
PAINT WHITE (-7962 -1816);
WIRE 16 -1 (-6975 -1575)(-8025 -1575);
FORCEPROP 2 LAST SIG_NAME PU_TAP_ODT_CPU1_EN
J 0
(-7960 -1565);
DISPLAY 0.553191 (-7960 -1565);
PAINT WHITE (-7960 -1565);
WIRE 16 -1 (-8575 -875)(-9575 -875);
FORCEPROP 2 LAST SIG_NAME SMB_S3M_CPU1_PIROM_3V3AUX_SCL
J 0
(-9510 -865);
DISPLAY 0.553191 (-9510 -865);
PAINT WHITE (-9510 -865);
WIRE 16 -1 (-6975 -1025)(-8025 -1025);
FORCEPROP 2 LAST SIG_NAME PU_PIROM_CPU1_ADDR0
J 0
(-7960 -1015);
DISPLAY 0.553191 (-7960 -1015);
PAINT WHITE (-7960 -1015);
WIRE 16 -1 (-6975 -1075)(-8025 -1075);
FORCEPROP 2 LAST SIG_NAME PD_PIROM_CPU1_ADDR1
J 0
(-7960 -1065);
DISPLAY 0.553191 (-7960 -1065);
PAINT WHITE (-7960 -1065);
WIRE 16 -1 (-6975 -1125)(-8025 -1125);
FORCEPROP 2 LAST SIG_NAME PD_PIROM_CPU1_ADDR2
J 0
(-7960 -1115);
DISPLAY 0.553191 (-7960 -1115);
PAINT WHITE (-7960 -1115);
WIRE 16 -1 (-6975 -1225)(-8025 -1225);
FORCEPROP 2 LAST SIG_NAME SMB_PEHPCPU1_GTL_SCL
J 0
(-7960 -1215);
DISPLAY 0.553191 (-7960 -1215);
PAINT WHITE (-7960 -1215);
WIRE 16 -1 (-6975 -1275)(-8025 -1275);
FORCEPROP 2 LAST SIG_NAME SMB_PEHPCPU1_GTL_SDA
J 0
(-7960 -1265);
DISPLAY 0.553191 (-7960 -1265);
PAINT WHITE (-7960 -1265);
WIRE 16 -1 (-6975 -1325)(-8025 -1325);
FORCEPROP 2 LAST SIG_NAME FM_PEHPCPU1_ALERT_N
J 0
(-7960 -1315);
DISPLAY 0.553191 (-7960 -1315);
PAINT WHITE (-7960 -1315);
WIRE 16 -1 (-6975 -2875)(-8025 -2875);
FORCEPROP 2 LAST SIG_NAME PWRGD_DRAMPWRGD_CPU1_AB_LVC1_R
J 0
(-7962 -2866);
DISPLAY 0.553191 (-7962 -2866);
PAINT WHITE (-7962 -2866);
WIRE 16 -1 (-6975 -2925)(-8025 -2925);
FORCEPROP 2 LAST SIG_NAME PWRGD_DRAMPWRGD_CPU1_CD_LVC1_R
J 0
(-7962 -2916);
DISPLAY 0.553191 (-7962 -2916);
PAINT WHITE (-7962 -2916);
WIRE 16 -1 (-6975 -2975)(-8025 -2975);
FORCEPROP 2 LAST SIG_NAME PWRGD_DRAMPWRGD_CPU1_EF_LVC1_R
J 0
(-7962 -2966);
DISPLAY 0.553191 (-7962 -2966);
PAINT WHITE (-7962 -2966);
WIRE 16 -1 (-6975 -3025)(-8025 -3025);
FORCEPROP 2 LAST SIG_NAME PWRGD_DRAMPWRGD_CPU1_GH_LVC1_R
J 0
(-7962 -3016);
DISPLAY 0.553191 (-7962 -3016);
PAINT WHITE (-7962 -3016);
WIRE 16 -1 (-6975 -1425)(-8025 -1425);
FORCEPROP 2 LAST SIG_NAME PD_CPU1_ENH_MCECC_DIS
J 0
(-7960 -1415);
DISPLAY 0.553191 (-7960 -1415);
PAINT WHITE (-7960 -1415);
WIRE 16 -1 (-6975 -875)(-8375 -875);
FORCEPROP 2 LAST SIG_NAME SMB_S3M_CPU1_PIROM_3V3AUX_SCL_R1
J 0
(-7960 -865);
DISPLAY 0.553191 (-7960 -865);
PAINT WHITE (-7960 -865);
WIRE 16 -1 (-6975 -925)(-8375 -925);
FORCEPROP 2 LAST SIG_NAME SMB_S3M_CPU1_PIROM_3V3AUX_SDA_R1
J 0
(-7960 -915);
DISPLAY 0.553191 (-7960 -915);
PAINT WHITE (-7960 -915);
WIRE 16 -1 (-6975 -975)(-8025 -975);
FORCEPROP 2 LAST SIG_NAME PU_PIROM_CPU1_SM_WP
J 0
(-7960 -965);
DISPLAY 0.553191 (-7960 -965);
PAINT WHITE (-7960 -965);
WIRE 16 -1 (-6975 -2625)(-8025 -2625);
FORCEPROP 2 LAST SIG_NAME TP_H_SBLINK7_CPU1_PMDOWN
J 0
(-7962 -2616);
DISPLAY 0.553191 (-7962 -2616);
PAINT WHITE (-7962 -2616);
WIRE 16 -1 (-6975 -2525)(-8025 -2525);
FORCEPROP 2 LAST SIG_NAME TP_H_SBLINK6_CPU1_PMDOWN
J 0
(-7962 -2516);
DISPLAY 0.553191 (-7962 -2516);
PAINT WHITE (-7962 -2516);
WIRE 16 -1 (-6975 -2425)(-8025 -2425);
FORCEPROP 2 LAST SIG_NAME TP_H_SBLINK5_CPU1_PMDOWN
J 0
(-7962 -2416);
DISPLAY 0.553191 (-7962 -2416);
PAINT WHITE (-7962 -2416);
WIRE 16 -1 (-6975 -2325)(-8025 -2325);
FORCEPROP 2 LAST SIG_NAME TP_H_SBLINK4_CPU1_PMDOWN
J 0
(-7962 -2316);
DISPLAY 0.553191 (-7962 -2316);
PAINT WHITE (-7962 -2316);
WIRE 16 -1 (-6975 -2225)(-8025 -2225);
FORCEPROP 2 LAST SIG_NAME TP_H_SBLINK3_CPU1_PMDOWN
J 0
(-7962 -2216);
DISPLAY 0.553191 (-7962 -2216);
PAINT WHITE (-7962 -2216);
WIRE 16 -1 (-6975 -2125)(-8025 -2125);
FORCEPROP 2 LAST SIG_NAME TP_H_SBLINK2_CPU1_PMDOWN
J 0
(-7962 -2116);
DISPLAY 0.553191 (-7962 -2116);
PAINT WHITE (-7962 -2116);
WIRE 16 -1 (-6975 -2025)(-8025 -2025);
FORCEPROP 2 LAST SIG_NAME H_CPU0_PMSYNC_CPU1
J 0
(-7962 -2016);
DISPLAY 0.553191 (-7962 -2016);
PAINT WHITE (-7962 -2016);
WIRE 16 -1 (-6975 -1925)(-8025 -1925);
FORCEPROP 2 LAST SIG_NAME TP_H_CPU1_PMDOWN_PCH_R
J 0
(-7962 -1916);
DISPLAY 0.553191 (-7962 -1916);
PAINT WHITE (-7962 -1916);
WIRE 16 -1 (-6975 -2575)(-8025 -2575);
FORCEPROP 2 LAST SIG_NAME TP_H_SBLINK7_CPU1_PMSYNC
J 0
(-7962 -2566);
DISPLAY 0.553191 (-7962 -2566);
PAINT WHITE (-7962 -2566);
WIRE 16 -1 (-6975 -2475)(-8025 -2475);
FORCEPROP 2 LAST SIG_NAME TP_H_SBLINK6_CPU1_PMSYNC
J 0
(-7962 -2466);
DISPLAY 0.553191 (-7962 -2466);
PAINT WHITE (-7962 -2466);
WIRE 16 -1 (-6975 -2375)(-8025 -2375);
FORCEPROP 2 LAST SIG_NAME TP_H_SBLINK5_CPU1_PMSYNC
J 0
(-7962 -2366);
DISPLAY 0.553191 (-7962 -2366);
PAINT WHITE (-7962 -2366);
WIRE 16 -1 (-6975 -2275)(-8025 -2275);
FORCEPROP 2 LAST SIG_NAME TP_H_SBLINK4_CPU1_PMSYNC
J 0
(-7962 -2266);
DISPLAY 0.553191 (-7962 -2266);
PAINT WHITE (-7962 -2266);
WIRE 16 -1 (-6975 -2175)(-8025 -2175);
FORCEPROP 2 LAST SIG_NAME TP_H_SBLINK3_CPU1_PMSYNC
J 0
(-7962 -2166);
DISPLAY 0.553191 (-7962 -2166);
PAINT WHITE (-7962 -2166);
WIRE 16 -1 (-6975 -2075)(-8025 -2075);
FORCEPROP 2 LAST SIG_NAME TP_H_SBLINK2_CPU1_PMSYNC
J 0
(-7962 -2066);
DISPLAY 0.553191 (-7962 -2066);
PAINT WHITE (-7962 -2066);
WIRE 16 -1 (-6975 -1975)(-8025 -1975);
FORCEPROP 2 LAST SIG_NAME H_CPU0_PMDOWN_CPU1
J 0
(-7962 -1966);
DISPLAY 0.553191 (-7962 -1966);
PAINT WHITE (-7962 -1966);
WIRE 16 -1 (-6975 -3075)(-8025 -3075);
FORCEPROP 2 LAST SIG_NAME PWRGD_CPU1_LVC1
J 0
(-7962 -3066);
DISPLAY 0.553191 (-7962 -3066);
PAINT WHITE (-7962 -3066);
WIRE 16 -1 (-6975 -3175)(-8025 -3175);
FORCEPROP 2 LAST SIG_NAME RST_CPU1_LVC1_N
J 0
(-7962 -3166);
DISPLAY 0.553191 (-7962 -3166);
PAINT WHITE (-7962 -3166);
WIRE 16 -1 (-6975 -1525)(-8025 -1525);
FORCEPROP 2 LAST SIG_NAME FM_CPU1_SKTOCC_LVT3_N
J 0
(-7960 -1515);
DISPLAY 0.553191 (-7960 -1515);
PAINT WHITE (-7960 -1515);
WIRE 16 -1 (-2850 -1525)(-4525 -1525);
FORCEPROP 2 LAST SIG_NAME H_CPU1_THERMTRIP_LVC1_R_N
J 0
(-4291 -1516);
DISPLAY 0.680851 (-4291 -1516);
PAINT WHITE (-4291 -1516);
WIRE 16 -1 (-2850 -1775)(-4525 -1775);
FORCEPROP 2 LAST SIG_NAME TP_EV_CPU1_EXT_BGREF
J 0
(-4291 -1766);
DISPLAY 0.680851 (-4291 -1766);
PAINT WHITE (-4291 -1766);
WIRE 16 -1 (-3500 -875)(-4525 -875);
FORCEPROP 2 LAST SIG_NAME SVID_DIO1_CPU1
J 0
(-4291 -866);
DISPLAY 0.680851 (-4291 -866);
PAINT WHITE (-4291 -866);
WIRE 16 -1 (-3500 -675)(-4525 -675);
FORCEPROP 2 LAST SIG_NAME SVID_DIO0_CPU1
J 0
(-4291 -666);
DISPLAY 0.680851 (-4291 -666);
PAINT WHITE (-4291 -666);
WIRE 16 -1 (-3500 -925)(-4525 -925);
FORCEPROP 2 LAST SIG_NAME SVID_CLK1_CPU1
J 0
(-4291 -916);
DISPLAY 0.680851 (-4291 -916);
PAINT WHITE (-4291 -916);
WIRE 16 -1 (-3500 -725)(-4525 -725);
FORCEPROP 2 LAST SIG_NAME SVID_CLK0_CPU1
J 0
(-4291 -716);
DISPLAY 0.680851 (-4291 -716);
PAINT WHITE (-4291 -716);
WIRE 16 -1 (-3500 -975)(-4525 -975);
FORCEPROP 2 LAST SIG_NAME SVID_ALERT1_CPU1_N
J 0
(-4291 -966);
DISPLAY 0.680851 (-4291 -966);
PAINT WHITE (-4291 -966);
WIRE 16 -1 (-3500 -775)(-4525 -775);
FORCEPROP 2 LAST SIG_NAME SVID_ALERT0_CPU1_N
J 0
(-4291 -766);
DISPLAY 0.680851 (-4291 -766);
PAINT WHITE (-4291 -766);
WIRE 16 -1 (-2850 -2875)(-4525 -2875);
FORCEPROP 2 LAST SIG_NAME CPU1_RSVD<98>
J 0
(-4291 -2866);
DISPLAY 0.680851 (-4291 -2866);
PAINT WHITE (-4291 -2866);
WIRE 16 -1 (-2850 -2375)(-4525 -2375);
FORCEPROP 2 LAST SIG_NAME CPU1_RSVD<65>
J 0
(-4291 -2366);
DISPLAY 0.680851 (-4291 -2366);
PAINT WHITE (-4291 -2366);
WIRE 16 -1 (-2850 -2425)(-4525 -2425);
FORCEPROP 2 LAST SIG_NAME CPU1_RSVD<64>
J 0
(-4291 -2416);
DISPLAY 0.680851 (-4291 -2416);
PAINT WHITE (-4291 -2416);
WIRE 16 -1 (-2850 -2225)(-4525 -2225);
FORCEPROP 2 LAST SIG_NAME CPU1_RSVD<6>
J 0
(-4291 -2216);
DISPLAY 0.680851 (-4291 -2216);
PAINT WHITE (-4291 -2216);
WIRE 16 -1 (-2850 -2525)(-4525 -2525);
FORCEPROP 2 LAST SIG_NAME CPU1_RSVD<54>
J 0
(-4291 -2516);
DISPLAY 0.680851 (-4291 -2516);
PAINT WHITE (-4291 -2516);
WIRE 16 -1 (-2850 -2175)(-4525 -2175);
FORCEPROP 2 LAST SIG_NAME CPU1_RSVD<4>
J 0
(-4291 -2166);
DISPLAY 0.680851 (-4291 -2166);
PAINT WHITE (-4291 -2166);
WIRE 16 -1 (-2850 -2475)(-4525 -2475);
FORCEPROP 2 LAST SIG_NAME CPU1_RSVD<27>
J 0
(-4291 -2466);
DISPLAY 0.680851 (-4291 -2466);
PAINT WHITE (-4291 -2466);
WIRE 16 -1 (-2850 -2125)(-4525 -2125);
FORCEPROP 2 LAST SIG_NAME CPU1_RSVD<25>
J 0
(-4291 -2116);
DISPLAY 0.680851 (-4291 -2116);
PAINT WHITE (-4291 -2116);
WIRE 16 -1 (-2850 -2275)(-4525 -2275);
FORCEPROP 2 LAST SIG_NAME CPU1_RSVD<15>
J 0
(-4291 -2266);
DISPLAY 0.680851 (-4291 -2266);
PAINT WHITE (-4291 -2266);
WIRE 16 -1 (-2850 -1975)(-4525 -1975);
FORCEPROP 2 LAST SIG_NAME CPU1_RSVD<144>
J 0
(-4291 -1966);
DISPLAY 0.680851 (-4291 -1966);
PAINT WHITE (-4291 -1966);
WIRE 16 -1 (-2850 -2675)(-4525 -2675);
FORCEPROP 2 LAST SIG_NAME CPU1_RSVD<140>
J 0
(-4291 -2666);
DISPLAY 0.680851 (-4291 -2666);
PAINT WHITE (-4291 -2666);
WIRE 16 -1 (-2850 -2775)(-4525 -2775);
FORCEPROP 2 LAST SIG_NAME CPU1_RSVD<139>
J 0
(-4291 -2766);
DISPLAY 0.680851 (-4291 -2766);
PAINT WHITE (-4291 -2766);
WIRE 16 -1 (-2850 -2725)(-4525 -2725);
FORCEPROP 2 LAST SIG_NAME CPU1_RSVD<135>
J 0
(-4291 -2716);
DISPLAY 0.680851 (-4291 -2716);
PAINT WHITE (-4291 -2716);
WIRE 16 -1 (-2850 -2625)(-4525 -2625);
FORCEPROP 2 LAST SIG_NAME CPU1_RSVD<126>
J 0
(-4291 -2616);
DISPLAY 0.680851 (-4291 -2616);
PAINT WHITE (-4291 -2616);
WIRE 16 -1 (-2850 -2925)(-4525 -2925);
FORCEPROP 2 LAST SIG_NAME CPU1_RSVD<120>
J 0
(-4291 -2916);
DISPLAY 0.680851 (-4291 -2916);
PAINT WHITE (-4291 -2916);
WIRE 16 -1 (-2850 -2975)(-4525 -2975);
FORCEPROP 2 LAST SIG_NAME CPU1_RSVD<115>
J 0
(-4291 -2966);
DISPLAY 0.680851 (-4291 -2966);
PAINT WHITE (-4291 -2966);
WIRE 16 -1 (-2850 -3025)(-4525 -3025);
FORCEPROP 2 LAST SIG_NAME CPU1_RSVD<110>
J 0
(-4291 -3016);
DISPLAY 0.680851 (-4291 -3016);
PAINT WHITE (-4291 -3016);
WIRE 16 -1 (-2850 -1325)(-4525 -1325);
FORCEPROP 2 LAST SIG_NAME H_CPU1_PROCHOT_LVC1_N
J 0
(-4291 -1316);
DISPLAY 0.680851 (-4291 -1316);
PAINT WHITE (-4291 -1316);
WIRE 16 -1 (-2850 -1825)(-4525 -1825);
FORCEPROP 2 LAST SIG_NAME H_CPU1_PM_FAST_WAKE_N
J 0
(-4291 -1816);
DISPLAY 0.680851 (-4291 -1816);
PAINT WHITE (-4291 -1816);
WIRE 16 -1 (-2850 -1575)(-4525 -1575);
FORCEPROP 2 LAST SIG_NAME H_CPU1_NMI_LVC1_N
J 0
(-4291 -1566);
DISPLAY 0.680851 (-4291 -1566);
PAINT WHITE (-4291 -1566);
WIRE 16 -1 (-2850 -1475)(-4525 -1475);
FORCEPROP 2 LAST SIG_NAME H_CPU1_MEMTRIP_LVC1_R_N
J 0
(-4291 -1466);
DISPLAY 0.680851 (-4291 -1466);
PAINT WHITE (-4291 -1466);
WIRE 16 -1 (-2850 -1425)(-4525 -1425);
FORCEPROP 2 LAST SIG_NAME H_CPU1_MEMHOT_OUT_LVC1_R_N
J 0
(-4291 -1416);
DISPLAY 0.680851 (-4291 -1416);
PAINT WHITE (-4291 -1416);
WIRE 16 -1 (-2850 -1375)(-4525 -1375);
FORCEPROP 2 LAST SIG_NAME H_CPU1_MEMHOT_IN_LVC1_N
J 0
(-4291 -1366);
DISPLAY 0.680851 (-4291 -1366);
PAINT WHITE (-4291 -1366);
WIRE 16 -1 (-2850 -1725)(-4525 -1725);
FORCEPROP 2 LAST SIG_NAME FM_CPU_FBRK_DEBUG_R_N
J 0
(-4291 -1716);
DISPLAY 0.680851 (-4291 -1716);
PAINT WHITE (-4291 -1716);
WIRE 16 -1 (-2850 -1075)(-4525 -1075);
FORCEPROP 2 LAST SIG_NAME H_CPU1_ERR0_LVC1_R_N
J 0
(-4291 -1066);
DISPLAY 0.680851 (-4291 -1066);
PAINT WHITE (-4291 -1066);
WIRE 16 -1 (-2850 -1125)(-4525 -1125);
FORCEPROP 2 LAST SIG_NAME H_CPU1_ERR1_LVC1_R_N
J 0
(-4291 -1116);
DISPLAY 0.680851 (-4291 -1116);
PAINT WHITE (-4291 -1116);
WIRE 16 -1 (-2850 -1175)(-4525 -1175);
FORCEPROP 2 LAST SIG_NAME H_CPU1_ERR2_LVC1_R_N
J 0
(-4291 -1166);
DISPLAY 0.680851 (-4291 -1166);
PAINT WHITE (-4291 -1166);
WIRE 16 -1 (-2850 -1275)(-4525 -1275);
FORCEPROP 2 LAST SIG_NAME H_CPU1_CATERR_LVC1_R_N
J 0
(-4291 -1266);
DISPLAY 0.680851 (-4291 -1266);
PAINT WHITE (-4291 -1266);
WIRE 16 -1 (-3175 -4525)(-4350 -4525);
FORCEPROP 0 LAST CDS_PHYS_NET_NAME SVID_DIO0_CPU0_R
J 0
(-3816 -4484);
PAINT MONO (-3816 -4484);
DISPLAY INVISIBLE (-3816 -4484);
FORCEPROP 2 LAST SIG_NAME SVID_DIO0_CPU1_R
J 0
(-4241 -4516);
DISPLAY 0.680851 (-4241 -4516);
PAINT WHITE (-4241 -4516);
WIRE 16 -1 (-3175 -4725)(-4350 -4725);
FORCEPROP 0 LAST CDS_PHYS_NET_NAME SVID_ALERT0_CPU0_R_N
J 0
(-3816 -4684);
PAINT MONO (-3816 -4684);
DISPLAY INVISIBLE (-3816 -4684);
FORCEPROP 2 LAST SIG_NAME SVID_ALERT0_CPU1_R_N
J 0
(-4241 -4716);
DISPLAY 0.680851 (-4241 -4716);
PAINT WHITE (-4241 -4716);
FORCEPROP 0 LAST $PHYS_NET_NAME SVID_ALERT0_CPU0_R_N
J 0
(-3816 -4637);
PAINT MONO (-3816 -4637);
DISPLAY INVISIBLE (-3816 -4637);
WIRE 16 -1 (-3175 -4925)(-4350 -4925);
FORCEPROP 0 LAST CDS_PHYS_NET_NAME SVID_DIO1_CPU0_R
J 0
(-3816 -4884);
PAINT MONO (-3816 -4884);
DISPLAY INVISIBLE (-3816 -4884);
FORCEPROP 2 LAST SIG_NAME SVID_DIO1_CPU1_R
J 0
(-4241 -4916);
DISPLAY 0.680851 (-4241 -4916);
PAINT WHITE (-4241 -4916);
WIRE 16 -1 (-2525 -5125)(-2975 -5125);
WIRE 16 -1 (-2525 -4925)(-2525 -5125);
WIRE 16 -1 (-2525 -4925)(-2975 -4925);
WIRE 16 -1 (-2525 -4725)(-2975 -4725);
WIRE 16 -1 (-2525 -4725)(-2525 -4925);
WIRE 16 -1 (-2525 -4525)(-2975 -4525);
WIRE 16 -1 (-2525 -4525)(-2525 -4725);
WIRE 16 -1 (-2050 -925)(-3300 -925);
FORCEPROP 2 LAST SIG_NAME SVID_CLK1_CPU1_R
J 0
(-2766 -916);
DISPLAY 0.680851 (-2766 -916);
PAINT WHITE (-2766 -916);
WIRE 16 -1 (-2050 -975)(-3300 -975);
FORCEPROP 2 LAST SIG_NAME SVID_ALERT1_CPU1_R_N
J 0
(-2766 -966);
DISPLAY 0.680851 (-2766 -966);
PAINT WHITE (-2766 -966);
WIRE 16 -1 (-8575 -925)(-9575 -925);
FORCEPROP 2 LAST SIG_NAME SMB_S3M_CPU1_PIROM_3V3AUX_SDA
J 0
(-9510 -915);
DISPLAY 0.553191 (-9510 -915);
PAINT WHITE (-9510 -915);
WIRE 16 -1 (-3175 -5125)(-4350 -5125);
FORCEPROP 0 LAST CDS_PHYS_NET_NAME SVID_CLK1_CPU0_R
J 0
(-3816 -5084);
PAINT MONO (-3816 -5084);
DISPLAY INVISIBLE (-3816 -5084);
FORCEPROP 2 LAST SIG_NAME SVID_ALERT1_CPU1_R_N
J 0
(-4241 -5116);
DISPLAY 0.680851 (-4241 -5116);
PAINT WHITE (-4241 -5116);
WIRE 16 -1 (-2050 -775)(-3300 -775);
FORCEPROP 2 LAST SIG_NAME SVID_ALERT0_CPU1_R_N
J 0
(-2766 -766);
DISPLAY 0.680851 (-2766 -766);
PAINT WHITE (-2766 -766);
WIRE 16 -1 (-2050 -725)(-3300 -725);
FORCEPROP 2 LAST SIG_NAME SVID_CLK0_CPU1_R
J 0
(-2766 -716);
DISPLAY 0.680851 (-2766 -716);
PAINT WHITE (-2766 -716);
WIRE 16 -1 (-2050 -675)(-3300 -675);
FORCEPROP 2 LAST SIG_NAME SVID_DIO0_CPU1_R
J 0
(-2766 -666);
DISPLAY 0.680851 (-2766 -666);
PAINT WHITE (-2766 -666);
WIRE 16 -1 (-2050 -875)(-3300 -875);
FORCEPROP 2 LAST SIG_NAME SVID_DIO1_CPU1_R
J 0
(-2766 -866);
DISPLAY 0.680851 (-2766 -866);
PAINT WHITE (-2766 -866);
DOT 1 (-2525 -4925);
DOT 1 (-2525 -4525);
DOT 1 (-2525 -4725);
FORCENOTE
20210818 MODIFY FOR GT
(-9975 -525) 0;
DISPLAY LEFT (-9975 -525);
DISPLAY 2.510638 (-9975 -525);
PAINT PINK (-9975 -525);
QUIT
